G04 ================== begin FILE IDENTIFICATION RECORD ==================*
G04 Layout Name:  D:/<user>/Wistron_project/16316-1/gbr-0621/16316-1.brd*
G04 Film Name:    SE_REF_L3*
G04 File Format:  Gerber RS274X*
G04 File Origin:  Cadence Allegro 16.5-S056*
G04 Origin Date:  Wed Jun 21 09:32:30 2017*
G04 *
G04 Layer:  BOARD GEOMETRY/SE_REF_L3_TBL*
G04 Layer:  BOARD GEOMETRY/SE_REF_L3_L3*
G04 Layer:  BOARD GEOMETRY/PANEL_OUTLINE*
G04 *
G04 Offset:    (0.00 0.00)*
G04 Mirror:    No*
G04 Mode:      Positive*
G04 Rotation:  0*
G04 FullContactRelief:  No*
G04 UndefLineWidth:     6.00*
G04 ================== end FILE IDENTIFICATION RECORD ====================*
%FSLAX35Y35*MOIN*%
%IR0*IPPOS*OFA0.00000B0.00000*MIA0B0*SFA1.00000B1.00000*%
%ADD10C,.02*%
%ADD11C,.005*%
%ADD12C,.006*%
G75*
%LPD*%
G75*
G54D10*
G01X877071Y467216D02*
X1594571D01*
G01X877071Y536516D02*
Y467216D01*
G01Y536516D02*
X1594571D01*
G01X877071Y501866D02*
X1594571D01*
G01X1052071Y536516D02*
Y467216D01*
G01X1279571Y536516D02*
Y467216D01*
G01X1384571Y536516D02*
Y467216D01*
G01X1594571Y536516D02*
Y467216D01*
G54D11*
G01X241826Y50267D02*
X314943D01*
G01X234693Y57400D02*
X241826Y50267D01*
G01X207500Y275246D02*
Y278400D01*
G01X219284Y263462D02*
X207500Y275246D01*
G01X248801Y263462D02*
X219284D01*
G01X258915Y253348D02*
X248801Y263462D01*
G01X266131Y253348D02*
X258915D01*
G01X291344Y266028D02*
X244627Y312745D01*
G01X224950Y275028D02*
X222320Y277658D01*
G01X253972Y275028D02*
X224950D01*
G01X264152Y264848D02*
X253972Y275028D01*
G01X248429Y286300D02*
X242402D01*
G01X265881Y268848D02*
X248429Y286300D01*
G01X204997Y274920D02*
Y280702D01*
G01X218518Y261399D02*
X204997Y274920D01*
G01X248035Y261399D02*
X218518D01*
G01X262206Y247228D02*
X248035Y261399D01*
G01X269422Y247228D02*
X262206D01*
G01X201148Y275940D02*
Y330641D01*
G01X219688Y257400D02*
X201148Y275940D01*
G01X249205Y257400D02*
X219688D01*
G01X264106Y242499D02*
X249205Y257400D01*
G01X247858Y289700D02*
X266710Y270848D01*
G01X242400Y289700D02*
X247858D01*
G01X262023Y260848D02*
X269239D01*
G01X251907Y270964D02*
X262023Y260848D01*
G01X222390Y270964D02*
X251907D01*
G01X215400Y277954D02*
X222390Y270964D01*
G01X215400Y305471D02*
Y277954D01*
G01X255500Y304743D02*
X290795Y269448D01*
G01X254837Y277063D02*
X265052Y266848D01*
G01X227337Y277063D02*
X254837D01*
G01X225500Y278900D02*
X227337Y277063D01*
G01X252736Y272964D02*
X262852Y262848D01*
G01X223219Y272964D02*
X252736D01*
G01X217400Y278783D02*
X223219Y272964D01*
G01X217400Y306600D02*
Y278783D01*
G01X227633Y345233D02*
X230400Y348000D01*
G01X227633Y321550D02*
Y345233D01*
G01X236438Y312745D02*
X227633Y321550D01*
G01X244627Y312745D02*
X236438D01*
G01X280535Y340111D02*
X241556D01*
G01X257500Y325443D02*
X253245Y329698D01*
G01X257500Y305572D02*
Y325443D01*
G01X291513Y271560D02*
X257500Y305572D01*
G01X201148Y330641D02*
X243679Y373172D01*
G01X208648Y312223D02*
X215400Y305471D01*
G01X208648Y328452D02*
Y312223D01*
G01X255500Y323881D02*
Y304743D01*
G01X253154Y326227D02*
X255500Y323881D01*
G01X239547Y337924D02*
X237483Y339988D01*
G01X279893Y337924D02*
X239547D01*
G01X234450Y335550D02*
X233400Y336600D01*
G01X260669Y335550D02*
X234450D01*
G01X267500Y328719D02*
X260669Y335550D01*
G01X212198Y311802D02*
X217400Y306600D01*
G01X212198Y328316D02*
Y311802D01*
G01X232950Y333550D02*
X230000Y336500D01*
G01X259654Y333550D02*
X232950D01*
G01X263442Y329762D02*
X259654Y333550D01*
G01X243679Y373172D02*
X264076D01*
G01X314943Y50267D02*
X323476Y58800D01*
G01D02*
X338944D01*
G01X316622Y110526D02*
X303490Y123658D01*
G01X316622Y107617D02*
Y110526D01*
G01X323569Y100670D02*
X316622Y107617D01*
G01X370303Y100670D02*
X323569D01*
G01X306280Y82574D02*
X357718D01*
G01X311182Y62800D02*
X347989D01*
G01X292359Y64800D02*
X348818D01*
G01X275402Y81757D02*
X292359Y64800D01*
G01X275402Y86902D02*
Y81757D01*
G01X272937Y89367D02*
X275402Y86902D01*
G01X272937Y90362D02*
Y89367D01*
G01X321777Y98670D02*
X301490Y118957D01*
G01X369474Y98670D02*
X321777D01*
G01X306591Y75074D02*
X304591Y73074D01*
G01X354610Y75074D02*
X306591D01*
G01X290804Y88574D02*
X360205D01*
G01X279385Y99993D02*
X290804Y88574D01*
G01X279385Y100227D02*
Y99993D01*
G01Y100227D02*
Y198285D01*
G01X299193Y66800D02*
X351568D01*
G01X266895Y99098D02*
X299193Y66800D01*
G01X266895Y100227D02*
Y99098D01*
G01X311942Y96670D02*
X363425D01*
G01X300385Y108227D02*
X311942Y96670D01*
G01X292030Y90574D02*
X361034D01*
G01X300280Y86574D02*
X296280Y82574D01*
G01X359376Y86574D02*
X300280D01*
G01X308591Y68928D02*
X352269D01*
G01X300311Y60800D02*
X345164D01*
G01X353781Y73074D02*
X308591D01*
G01X306737Y71074D02*
X304591Y68928D01*
G01X352952Y71074D02*
X306737D01*
G01X303280Y84574D02*
X301280Y82574D01*
G01X358547Y84574D02*
X303280D01*
G01X284411Y155991D02*
Y201889D01*
G01X303490Y136912D02*
X284411Y155991D01*
G01X303490Y123658D02*
Y136912D01*
G01X316924Y132561D02*
Y178465D01*
G01X337315Y112170D02*
X316924Y132561D01*
G01X321146Y136854D02*
Y185043D01*
G01X325630Y132370D02*
X321146Y136854D01*
G01X282256Y154977D02*
Y201073D01*
G01X301490Y135743D02*
X282256Y154977D01*
G01X301490Y118957D02*
Y135743D01*
G01X323940Y136973D02*
X333512Y127401D01*
G01X323940Y186684D02*
Y136973D01*
G01X322086Y120493D02*
X325876Y116703D01*
G01X320576Y120493D02*
X322086D01*
G01X312581Y128488D02*
X320576Y120493D01*
G01X312581Y139925D02*
Y128488D01*
G01X304882Y147624D02*
X312581Y139925D01*
G01X304882Y177609D02*
Y147624D01*
G01X318924Y133390D02*
X338144Y114170D01*
G01X318924Y181865D02*
Y133390D01*
G01X314581Y132075D02*
X336486Y110170D01*
G01X314581Y175208D02*
Y132075D01*
G01X310021Y179768D02*
X314581Y175208D01*
G01X279881Y206419D02*
Y239598D01*
G01X284411Y201889D02*
X279881Y206419D01*
G01X319157Y236514D02*
X302264Y253407D01*
G01X319157Y201069D02*
Y236514D01*
G01X329940Y190286D02*
X319157Y201069D01*
G01X291384Y228653D02*
Y244361D01*
G01X302866Y217171D02*
X291384Y228653D01*
G01X302866Y190377D02*
Y217171D01*
G01X308158Y185085D02*
X302866Y190377D01*
G01X310304Y185085D02*
X308158D01*
G01X316924Y178465D02*
X310304Y185085D01*
G01X323157Y202727D02*
X333940Y191944D01*
G01X323157Y239109D02*
Y202727D01*
G01X300302Y225497D02*
Y241101D01*
G01X308137Y217662D02*
X300302Y225497D01*
G01X310127Y217662D02*
X308137D01*
G01X311157Y216632D02*
X310127Y217662D01*
G01X311157Y195032D02*
Y216632D01*
G01X321146Y185043D02*
X311157Y195032D01*
G01X277881Y205448D02*
Y238769D01*
G01X282256Y201073D02*
X277881Y205448D01*
G01X275600Y237346D02*
X270447Y242499D01*
G01X275600Y202070D02*
Y237346D01*
G01X279385Y198285D02*
X275600Y202070D01*
G01X313157Y197467D02*
X323940Y186684D01*
G01X313157Y225432D02*
Y197467D01*
G01X309862Y228727D02*
X313157Y225432D01*
G01X307369Y228727D02*
X309862D01*
G01X302302Y233794D02*
X307369Y228727D01*
G01X302302Y241930D02*
Y233794D01*
G01X317157Y199324D02*
X327940Y188541D01*
G01X317157Y232232D02*
Y199324D01*
G01X309974Y239415D02*
X317157Y232232D01*
G01X321157Y201898D02*
X331940Y191115D01*
G01X321157Y237960D02*
Y201898D01*
G01X298657Y183834D02*
X304882Y177609D01*
G01X298657Y215722D02*
Y183834D01*
G01X287384Y226995D02*
X298657Y215722D01*
G01X287384Y242703D02*
Y226995D01*
G01X304302Y237256D02*
Y243934D01*
G01X307808Y233750D02*
X304302Y237256D01*
G01X310239Y233750D02*
X307808D01*
G01X315157Y228832D02*
X310239Y233750D01*
G01X315157Y198495D02*
Y228832D01*
G01X325940Y187712D02*
X315157Y198495D01*
G01X309864Y190925D02*
X318924Y181865D01*
G01X307787Y190925D02*
X309864D01*
G01X304866Y193846D02*
X307787Y190925D01*
G01X304866Y218000D02*
Y193846D01*
G01X293384Y229482D02*
X304866Y218000D01*
G01X293384Y245190D02*
Y229482D01*
G01X308352Y179768D02*
X310021D01*
G01X300657Y187463D02*
X308352Y179768D01*
G01X300657Y216551D02*
Y187463D01*
G01X289384Y227824D02*
X300657Y216551D01*
G01X289384Y243532D02*
Y227824D01*
G01X279881Y239598D02*
X266131Y253348D01*
G01X294231Y266028D02*
X291344D01*
G01X302264Y257995D02*
X294231Y266028D01*
G01X302264Y253407D02*
Y257995D01*
G01X270897Y264848D02*
X264152D01*
G01X291384Y244361D02*
X270897Y264848D01*
G01X322165Y270380D02*
X336279Y256266D01*
G01X317236Y270380D02*
X322165D01*
G01X304041Y283575D02*
X317236Y270380D01*
G01X301721Y283575D02*
X304041D01*
G01X297029Y288267D02*
X301721Y283575D01*
G01X292225Y288267D02*
X297029D01*
G01X306020Y256246D02*
X323157Y239109D01*
G01X306020Y258884D02*
Y256246D01*
G01X302262Y262642D02*
X306020Y258884D01*
G01X276979Y268848D02*
X265881D01*
G01X288612Y257215D02*
X276979Y268848D01*
G01X288612Y252791D02*
Y257215D01*
G01X300302Y241101D02*
X288612Y252791D01*
G01X288850Y288870D02*
Y306347D01*
G01X296160Y281560D02*
X288850Y288870D01*
G01X303227Y281560D02*
X296160D01*
G01X316407Y268380D02*
X303227Y281560D01*
G01X320749Y268380D02*
X316407D01*
G01X334279Y254850D02*
X320749Y268380D01*
G01X277881Y238769D02*
X269422Y247228D01*
G01X299002Y271560D02*
X291513D01*
G01X311775Y258787D02*
X299002Y271560D01*
G01X311775Y256809D02*
Y258787D01*
G01X327157Y241427D02*
X311775Y256809D01*
G01X270447Y242499D02*
X264106D01*
G01X293629Y250603D02*
X302302Y241930D01*
G01X293629Y256172D02*
Y250603D01*
G01X289773Y260028D02*
X293629Y256172D01*
G01X288628Y260028D02*
X289773D01*
G01X277808Y270848D02*
X288628Y260028D01*
G01X266710Y270848D02*
X277808D01*
G01X307930Y239415D02*
X309974D01*
G01X306303Y241042D02*
X307930Y239415D01*
G01X306303Y246539D02*
Y241042D01*
G01X300264Y252578D02*
X306303Y246539D01*
G01X300264Y257166D02*
Y252578D01*
G01X293402Y264028D02*
X300264Y257166D01*
G01X290286Y264028D02*
X293402D01*
G01X279466Y274848D02*
X290286Y264028D01*
G01X269393Y274848D02*
X279466D01*
G01X266406Y277835D02*
X269393Y274848D01*
G01X306292Y252825D02*
X321157Y237960D01*
G01X269239Y260848D02*
X287384Y242703D01*
G01X301358Y288650D02*
X299635D01*
G01X304449Y285559D02*
X301358Y288650D01*
G01X304886Y285559D02*
X304449D01*
G01X318065Y272380D02*
X304886Y285559D01*
G01X322994Y272380D02*
X318065D01*
G01X338279Y257095D02*
X322994Y272380D01*
G01X267787Y272848D02*
X262800Y277835D01*
G01X278637Y272848D02*
X267787D01*
G01X289457Y262028D02*
X278637Y272848D01*
G01X292573Y262028D02*
X289457D01*
G01X298263Y256338D02*
X292573Y262028D01*
G01X298263Y249973D02*
Y256338D01*
G01X304302Y243934D02*
X298263Y249973D01*
G01X324700Y292245D02*
X314045Y302900D01*
G01X324700Y289000D02*
Y292245D01*
G01X330438Y283262D02*
X324700Y289000D01*
G01X309705Y256050D02*
X325157Y240598D01*
G01X309705Y258028D02*
Y256050D01*
G01X298285Y269448D02*
X309705Y258028D01*
G01X290795Y269448D02*
X298285D01*
G01X322914Y257173D02*
X326298D01*
G01X321831Y258256D02*
X322914Y257173D01*
G01X321831Y259690D02*
Y258256D01*
G01X317572Y263949D02*
X321831Y259690D01*
G01X315180Y263949D02*
X317572D01*
G01X301569Y277560D02*
X315180Y263949D01*
G01X294267Y277560D02*
X301569D01*
G01X278579Y293248D02*
X294267Y277560D01*
G01X278579Y329429D02*
Y293248D01*
G01X286850Y288041D02*
Y305518D01*
G01X295331Y279560D02*
X286850Y288041D01*
G01X302398Y279560D02*
X295331D01*
G01X315856Y266102D02*
X302398Y279560D01*
G01X320198Y266102D02*
X315856D01*
G01X332279Y254021D02*
X320198Y266102D01*
G01X293438Y275560D02*
X267500Y301498D01*
G01X300740Y275560D02*
X293438D01*
G01X317958Y258342D02*
X300740Y275560D01*
G01X317958Y256284D02*
Y258342D01*
G01X331157Y243085D02*
X317958Y256284D01*
G01X271726Y266848D02*
X293384Y245190D01*
G01X265052Y266848D02*
X271726D01*
G01X270068Y262848D02*
X289384Y243532D01*
G01X262852Y262848D02*
X270068D01*
G01X292342Y273560D02*
X263442Y302459D01*
G01X299911Y273560D02*
X292342D01*
G01X314657Y258814D02*
X299911Y273560D01*
G01X314657Y256756D02*
Y258814D01*
G01X329157Y242256D02*
X314657Y256756D01*
G01X336738Y285262D02*
X316800Y305200D01*
G01X325300Y330600D02*
X319100D01*
G01X308194Y313945D02*
X326077D01*
G01X301628Y320511D02*
X308194Y313945D01*
G01X316450Y342600D02*
X316050Y342200D01*
G01X318024Y342600D02*
X316450D01*
G01X318524Y343100D02*
X318024Y342600D01*
G01X318524Y344100D02*
Y343100D01*
G01X319024Y344600D02*
X318524Y344100D01*
G01X320024Y344600D02*
X319024D01*
G01X320524Y344100D02*
X320024Y344600D01*
G01X320524Y342827D02*
Y344100D01*
G01X321024Y342327D02*
X320524Y342827D01*
G01X323489Y342327D02*
X321024D01*
G01X334881Y353719D02*
X323489Y342327D01*
G01X285763Y334883D02*
X280535Y340111D01*
G01X285763Y309434D02*
Y334883D01*
G01X288850Y306347D02*
X285763Y309434D01*
G01X314900Y311300D02*
X314300Y311900D01*
G01X325893Y311300D02*
X314900D01*
G01X309400Y354706D02*
X305147D01*
G01X309900Y354206D02*
X309400Y354706D01*
G01X309900Y351600D02*
Y354206D01*
G01X309400Y351100D02*
X309900Y351600D01*
G01X293500Y351100D02*
X309400D01*
G01X293000Y351600D02*
X293500Y351100D01*
G01X293000Y352900D02*
Y351600D01*
G01X293500Y353400D02*
X293000Y352900D01*
G01X302100Y353400D02*
X293500D01*
G01X302600Y353900D02*
X302100Y353400D01*
G01X302600Y355000D02*
Y353900D01*
G01X302100Y355500D02*
X302600Y355000D01*
G01X290629Y355500D02*
X302100D01*
G01X289900Y354771D02*
X290629Y355500D01*
G01X289900Y349800D02*
Y354771D01*
G01X290786Y348914D02*
X289900Y349800D01*
G01X310285Y348914D02*
X290786D01*
G01X313505Y352134D02*
X310285Y348914D01*
G01X313505Y352840D02*
Y352134D01*
G01X312476Y353868D02*
X313505Y352840D01*
G01X312476Y354574D02*
Y353868D01*
G01X313185Y355283D02*
X312476Y354574D01*
G01X313891Y355283D02*
X313185D01*
G01X314408Y354767D02*
X313891Y355283D01*
G01X314874Y354301D02*
X314408Y354767D01*
G01X317572Y354301D02*
X314874D01*
G01X320971Y357700D02*
X317572Y354301D01*
G01X321271Y357700D02*
X320971D01*
G01X321280Y357709D02*
X321271Y357700D01*
G01X326629Y357709D02*
X321280D01*
G01X275700Y346579D02*
X297021D01*
G01X275200Y346079D02*
X275700Y346579D01*
G01X275200Y344800D02*
Y346079D01*
G01X275700Y344300D02*
X275200Y344800D01*
G01X300400Y344300D02*
X275700D01*
G01X302600Y346500D02*
X300400Y344300D01*
G01X310700Y346500D02*
X302600D01*
G01X316501Y352301D02*
X310700Y346500D01*
G01X318401Y352301D02*
X316501D01*
G01X321800Y355700D02*
X318401Y352301D01*
G01X322100Y355700D02*
X321800D01*
G01X322109Y355709D02*
X322100Y355700D01*
G01X327458Y355709D02*
X322109D01*
G01X324100Y307814D02*
X327656Y304258D01*
G01X315749Y324251D02*
X314500D01*
G01X316600Y323400D02*
X315749Y324251D01*
G01X336199Y323400D02*
X316600D01*
G01X321624Y335482D02*
X320650Y336456D01*
G01X342028Y335482D02*
X321624D01*
G01X298055Y361700D02*
X297555Y362200D01*
G01X299555D02*
X299055Y361700D01*
G01X302055Y361600D02*
X301555Y362100D01*
G01X303055Y361600D02*
X302055D01*
G01X303555Y362100D02*
X303055Y361600D01*
G01X306055D02*
X305555Y362100D01*
G01X307055Y361600D02*
X306055D01*
G01X307555Y362100D02*
X307055Y361600D01*
G01X310055D02*
X309555Y362100D01*
G01X311055Y361600D02*
X310055D01*
G01X311555Y362100D02*
X311055Y361600D01*
G01X314055Y361500D02*
X313555Y362000D01*
G01X315055Y361500D02*
X314055D01*
G01X315555Y362000D02*
X315055Y361500D01*
G01X310194Y315945D02*
X305628Y320511D01*
G01X326906Y315945D02*
X310194D01*
G01X317269Y347169D02*
X319550D01*
G01X312427Y342327D02*
X317269Y347169D01*
G01X305300Y342327D02*
X312427D01*
G01X302686Y339713D02*
X305300Y342327D01*
G01X294400Y339713D02*
X302686D01*
G01X293900Y340213D02*
X294400Y339713D01*
G01X293900Y341800D02*
Y340213D01*
G01X294400Y342300D02*
X293900Y341800D01*
G01X301229Y342300D02*
X294400D01*
G01X303429Y344500D02*
X301229Y342300D01*
G01X311529Y344500D02*
X303429D01*
G01X317329Y350300D02*
X311529Y344500D01*
G01X319871Y350300D02*
X317329D01*
G01X321800Y348371D02*
X319871Y350300D01*
G01X321800Y345819D02*
Y348371D01*
G01X322300Y345319D02*
X321800Y345819D01*
G01X323619Y345319D02*
X322300D01*
G01X324100Y345800D02*
X323619Y345319D01*
G01X324100Y347500D02*
Y345800D01*
G01X324600Y348000D02*
X324100Y347500D01*
G01X326300Y348000D02*
X324600D01*
G01X281150Y332000D02*
X278579Y329429D01*
G01X319827Y338327D02*
X328802D01*
G01X317200Y335700D02*
X319827Y338327D01*
G01X312100Y335700D02*
X317200D01*
G01X310200Y337600D02*
X312100Y335700D01*
G01X324046Y327400D02*
X338000D01*
G01X323546Y326900D02*
X324046Y327400D01*
G01X323546Y325900D02*
Y326900D01*
G01X323046Y325400D02*
X323546Y325900D01*
G01X322046Y325400D02*
X323046D01*
G01X321546Y325900D02*
X322046Y325400D01*
G01X321546Y327900D02*
Y325900D01*
G01X321046Y328400D02*
X321546Y327900D01*
G01X320046Y328400D02*
X321046D01*
G01X319546Y327900D02*
X320046Y328400D01*
G01X319546Y325900D02*
Y327900D01*
G01X319046Y325400D02*
X319546Y325900D01*
G01X318046Y325400D02*
X319046D01*
G01X317546Y325900D02*
X318046Y325400D01*
G01X317546Y328100D02*
Y325900D01*
G01X317046Y328600D02*
X317546Y328100D01*
G01X315149Y328600D02*
X317046D01*
G01X314400Y327851D02*
X315149Y328600D01*
G01X283763Y334054D02*
X279893Y337924D01*
G01X283763Y308605D02*
Y334054D01*
G01X286850Y305518D02*
X283763Y308605D01*
G01X267500Y301498D02*
Y328719D01*
G01X310218Y333482D02*
X306060Y337640D01*
G01X341199Y333482D02*
X310218D01*
G01X318998Y340327D02*
X327973D01*
G01X316535Y337864D02*
X318998Y340327D01*
G01X312765Y337864D02*
X316535D01*
G01X310302Y340327D02*
X312765Y337864D01*
G01X306129Y340327D02*
X310302D01*
G01X304151Y338349D02*
X306129Y340327D01*
G01X304151Y327100D02*
Y338349D01*
G01X303651Y326600D02*
X304151Y327100D01*
G01X302300Y326600D02*
X303651D01*
G01X301800Y327100D02*
X302300Y326600D01*
G01X301800Y334200D02*
Y327100D01*
G01X301300Y334700D02*
X301800Y334200D01*
G01X300300Y334700D02*
X301300D01*
G01X299800Y334200D02*
X300300Y334700D01*
G01X299800Y327200D02*
Y334200D01*
G01X299300Y326700D02*
X299800Y327200D01*
G01X298000Y326700D02*
X299300D01*
G01X297500Y327200D02*
X298000Y326700D01*
G01X297500Y337000D02*
Y327200D01*
G01X298000Y337500D02*
X297500Y337000D01*
G01X301500Y337500D02*
X298000D01*
G01X287350Y352550D02*
Y351200D01*
G01X286700Y353200D02*
X287350Y352550D01*
G01X277500Y353200D02*
X286700D01*
G01X277000Y353700D02*
X277500Y353200D01*
G01X277000Y354975D02*
Y353700D01*
G01X277500Y355475D02*
X277000Y354975D01*
G01X287775Y355475D02*
X277500D01*
G01X289800Y357500D02*
X287775Y355475D01*
G01X317371Y357500D02*
X289800D01*
G01X319580Y359709D02*
X317371Y357500D01*
G01X325800Y359709D02*
X319580D01*
G01X316641Y308459D02*
X314241D01*
G01X320723Y304377D02*
X316641Y308459D01*
G01X321431Y304377D02*
X320723D01*
G01X322323Y305269D02*
X321431Y304377D01*
G01X323031Y305269D02*
X322323D01*
G01X323738Y304562D02*
X323031Y305269D01*
G01X323738Y303854D02*
Y304562D01*
G01X322846Y302962D02*
X323738Y303854D01*
G01X322846Y302254D02*
Y302962D01*
G01X323553Y301547D02*
X322846Y302254D01*
G01X324261Y301547D02*
X323553D01*
G01X325153Y302439D02*
X324261Y301547D01*
G01X263442Y302459D02*
Y329762D01*
G01X316800Y305200D02*
X308180D01*
G01X310780Y319359D02*
X305628Y324511D01*
G01X329785Y319359D02*
X310780D01*
G01X271300Y357700D02*
X287350D01*
G01X270800Y358200D02*
X271300Y357700D01*
G01X270800Y359500D02*
Y358200D01*
G01X271300Y360000D02*
X270800Y359500D01*
G01X287900Y360000D02*
X271300D01*
G01X288400Y360500D02*
X287900Y360000D01*
G01X288400Y361500D02*
Y360500D01*
G01X287900Y362000D02*
X288400Y361500D01*
G01X294259Y359500D02*
X289600Y364159D01*
G01X316384Y359500D02*
X294259D01*
G01X318593Y361709D02*
X316384Y359500D01*
G01X322500Y350500D02*
Y353700D01*
G01X323000Y350000D02*
X322500Y350500D01*
G01X324644Y350000D02*
X323000D01*
G01X325144Y350500D02*
X324644Y350000D01*
G01X324749Y381556D02*
X325749D01*
G01X324249Y381056D02*
X324749Y381556D01*
G01X324249Y378239D02*
Y381056D01*
G01X323749Y377739D02*
X324249Y378239D01*
G01X322749Y377739D02*
X323749D01*
G01X322249Y378239D02*
X322749Y377739D01*
G01X322249Y381056D02*
Y378239D01*
G01X321749Y381556D02*
X322249Y381056D01*
G01X320749Y381556D02*
X321749D01*
G01X320249Y381056D02*
X320749Y381556D01*
G01X320249Y378326D02*
Y381056D01*
G01X319749Y377826D02*
X320249Y378326D01*
G01X318749Y377826D02*
X319749D01*
G01X318249Y378326D02*
X318749Y377826D01*
G01X318249Y381056D02*
Y378326D01*
G01X317749Y381556D02*
X318249Y381056D01*
G01X316749Y381556D02*
X317749D01*
G01X316249Y381056D02*
X316749Y381556D01*
G01X316249Y378500D02*
Y381056D01*
G01X315749Y378000D02*
X316249Y378500D01*
G01X314749Y378000D02*
X315749D01*
G01X314249Y378500D02*
X314749Y378000D01*
G01X314249Y381056D02*
Y378500D01*
G01X313749Y381556D02*
X314249Y381056D01*
G01X312749Y381556D02*
X313749D01*
G01X312249Y381056D02*
X312749Y381556D01*
G01X312249Y378543D02*
Y381056D01*
G01X311749Y378043D02*
X312249Y378543D01*
G01X310749Y378043D02*
X311749D01*
G01X310249Y378543D02*
X310749Y378043D01*
G01X310249Y381056D02*
Y378543D01*
G01X309749Y381556D02*
X310249Y381056D01*
G01X308749Y381556D02*
X309749D01*
G01X308249Y381056D02*
X308749Y381556D01*
G01X308249Y378543D02*
Y381056D01*
G01X307749Y378043D02*
X308249Y378543D01*
G01X304705Y378043D02*
X307749D01*
G01X304205Y378543D02*
X304705Y378043D01*
G01X304205Y382450D02*
Y378543D01*
G01X324558Y388430D02*
X325058Y387930D01*
G01X323558Y388430D02*
X324558D01*
G01X323058Y387930D02*
X323558Y388430D01*
G01X323058Y386243D02*
Y387930D01*
G01X322558Y385743D02*
X323058Y386243D01*
G01X321558Y385743D02*
X322558D01*
G01X321058Y386243D02*
X321558Y385743D01*
G01X321058Y387930D02*
Y386243D01*
G01X320558Y388430D02*
X321058Y387930D01*
G01X319558Y388430D02*
X320558D01*
G01X319058Y387930D02*
X319558Y388430D01*
G01X319058Y386329D02*
Y387930D01*
G01X318558Y385829D02*
X319058Y386329D01*
G01X317558Y385829D02*
X318558D01*
G01X317058Y386329D02*
X317558Y385829D01*
G01X317058Y387930D02*
Y386329D01*
G01X316558Y388430D02*
X317058Y387930D01*
G01X315558Y388430D02*
X316558D01*
G01X315058Y387930D02*
X315558Y388430D01*
G01X315058Y386979D02*
Y387930D01*
G01X314558Y386479D02*
X315058Y386979D01*
G01X312398Y386479D02*
X314558D01*
G01X296231Y399596D02*
X332161D01*
G01X283435Y386800D02*
X296231Y399596D01*
G01X277704Y386800D02*
X283435D01*
G01X264076Y373172D02*
X277704Y386800D01*
G01X307244Y383633D02*
X327608D01*
G01X304398Y386479D02*
X307244Y383633D01*
G01X294700Y367324D02*
X325124D01*
G01X294200Y366824D02*
X294700Y367324D01*
G01X294200Y365600D02*
Y366824D01*
G01X294700Y365100D02*
X294200Y365600D01*
G01X297055Y365100D02*
X294700D01*
G01X297555Y364600D02*
X297055Y365100D01*
G01X297555Y362200D02*
Y364600D01*
G01X299055Y361700D02*
X298055D01*
G01X299555Y364600D02*
Y362200D01*
G01X300055Y365100D02*
X299555Y364600D01*
G01X301055Y365100D02*
X300055D01*
G01X301555Y364600D02*
X301055Y365100D01*
G01X301555Y362100D02*
Y364600D01*
G01X303555D02*
Y362100D01*
G01X304055Y365100D02*
X303555Y364600D01*
G01X305055Y365100D02*
X304055D01*
G01X305555Y364600D02*
X305055Y365100D01*
G01X305555Y362100D02*
Y364600D01*
G01X307555D02*
Y362100D01*
G01X308055Y365100D02*
X307555Y364600D01*
G01X309055Y365100D02*
X308055D01*
G01X309555Y364600D02*
X309055Y365100D01*
G01X309555Y362100D02*
Y364600D01*
G01X311555D02*
Y362100D01*
G01X312055Y365100D02*
X311555Y364600D01*
G01X313055Y365100D02*
X312055D01*
G01X313555Y364600D02*
X313055Y365100D01*
G01X313555Y362000D02*
Y364600D01*
G01X315555D02*
Y362000D01*
G01X316055Y365100D02*
X315555Y364600D01*
G01X325200Y365100D02*
X316055D01*
G01X300019Y376865D02*
Y379524D01*
G01X299519Y376365D02*
X300019Y376865D01*
G01X295800Y376365D02*
X299519D01*
G01X295300Y375865D02*
X295800Y376365D01*
G01X295300Y373868D02*
Y375865D01*
G01X295800Y373368D02*
X295300Y373868D01*
G01X301846Y373368D02*
X295800D01*
G01X302346Y373868D02*
X301846Y373368D01*
G01X302346Y375722D02*
Y373868D01*
G01X302846Y376222D02*
X302346Y375722D01*
G01X303846Y376222D02*
X302846D01*
G01X304346Y375722D02*
X303846Y376222D01*
G01X304346Y373868D02*
Y375722D01*
G01X304846Y373368D02*
X304346Y373868D01*
G01X305846Y373368D02*
X304846D01*
G01X306346Y373868D02*
X305846Y373368D01*
G01X306346Y375333D02*
Y373868D01*
G01X306846Y375833D02*
X306346Y375333D01*
G01X307846Y375833D02*
X306846D01*
G01X308346Y375333D02*
X307846Y375833D01*
G01X308346Y373868D02*
Y375333D01*
G01X308846Y373368D02*
X308346Y373868D01*
G01X309846Y373368D02*
X308846D01*
G01X310346Y373868D02*
X309846Y373368D01*
G01X310346Y375333D02*
Y373868D01*
G01X310846Y375833D02*
X310346Y375333D01*
G01X311846Y375833D02*
X310846D01*
G01X312346Y375333D02*
X311846Y375833D01*
G01X312346Y373868D02*
Y375333D01*
G01X312846Y373368D02*
X312346Y373868D01*
G01X313846Y373368D02*
X312846D01*
G01X314346Y373868D02*
X313846Y373368D01*
G01X314346Y375333D02*
Y373868D01*
G01X314846Y375833D02*
X314346Y375333D01*
G01X315846Y375833D02*
X314846D01*
G01X316346Y375333D02*
X315846Y375833D01*
G01X316346Y373868D02*
Y375333D01*
G01X316846Y373368D02*
X316346Y373868D01*
G01X317846Y373368D02*
X316846D01*
G01X318346Y373868D02*
X317846Y373368D01*
G01X318346Y375333D02*
Y373868D01*
G01X318839Y375826D02*
X318346Y375333D01*
G01X319853Y375826D02*
X318839D01*
G01X320346Y375333D02*
X319853Y375826D01*
G01X320346Y373868D02*
Y375333D01*
G01X320890Y373324D02*
X320346Y373868D01*
G01X322237Y373324D02*
X320890D01*
G01X326463Y377550D02*
X322237Y373324D01*
G01X296079Y381604D02*
Y379524D01*
G01X302954Y388479D02*
X296079Y381604D01*
G01X307422Y388479D02*
X302954D01*
G01X307922Y388979D02*
X307422Y388479D01*
G01X307922Y390802D02*
Y388979D01*
G01X307422Y391302D02*
X307922Y390802D01*
G01X301732Y391302D02*
X307422D01*
G01X292959Y382529D02*
X301732Y391302D01*
G01X292959Y378163D02*
Y382529D01*
G01X292459Y377663D02*
X292959Y378163D01*
G01X290438Y377663D02*
X292459D01*
G01X289938Y377163D02*
X290438Y377663D01*
G01X289938Y376163D02*
Y377163D01*
G01X290438Y375663D02*
X289938Y376163D01*
G01X292495Y375663D02*
X290438D01*
G01X292995Y375163D02*
X292495Y375663D01*
G01X292995Y374163D02*
Y375163D01*
G01X292495Y373663D02*
X292995Y374163D01*
G01X290438Y373663D02*
X292495D01*
G01X289938Y373163D02*
X290438Y373663D01*
G01X289938Y371824D02*
Y373163D01*
G01X290438Y371324D02*
X289938Y371824D01*
G01X323066Y371324D02*
X290438D01*
G01X327292Y375550D02*
X323066Y371324D01*
G01X312419Y390500D02*
X353000D01*
G01X308398Y386479D02*
X312419Y390500D01*
G01X323895Y369324D02*
X328121Y373550D01*
G01X288389Y369324D02*
X323895D01*
G01X287889Y369824D02*
X288389Y369324D01*
G01X287889Y375700D02*
Y369824D01*
G01X287389Y376200D02*
X287889Y375700D01*
G01X286389Y376200D02*
X287389D01*
G01X285889Y375700D02*
X286389Y376200D01*
G01X285889Y369824D02*
Y375700D01*
G01X285389Y369324D02*
X285889Y369824D01*
G01X284389Y369324D02*
X285389D01*
G01X283889Y369824D02*
X284389Y369324D01*
G01X283889Y375800D02*
Y369824D01*
G01X283389Y376300D02*
X283889Y375800D01*
G01X282389Y376300D02*
X283389D01*
G01X281889Y375800D02*
X282389Y376300D01*
G01X281889Y369824D02*
Y375800D01*
G01X281389Y369324D02*
X281889Y369824D01*
G01X280389Y369324D02*
X281389D01*
G01X279889Y369824D02*
X280389Y369324D01*
G01X279889Y373400D02*
Y369824D01*
G01X279389Y373900D02*
X279889Y373400D01*
G01X278389Y373900D02*
X279389D01*
G01X277889Y373400D02*
X278389Y373900D01*
G01X277889Y369824D02*
Y373400D01*
G01X277389Y369324D02*
X277889Y369824D01*
G01X274100Y369324D02*
X277389D01*
G01X273600Y368824D02*
X274100Y369324D01*
G01X273600Y366659D02*
Y368824D01*
G01X274100Y366159D02*
X273600Y366659D01*
G01X290441Y366159D02*
X274100D01*
G01X292800Y363800D02*
X290441Y366159D01*
G01X274200Y362000D02*
X287900D01*
G01X273700Y362500D02*
X274200Y362000D01*
G01X273700Y363659D02*
Y362500D01*
G01X274200Y364159D02*
X273700Y363659D01*
G01X289600Y364159D02*
X274200D01*
G01X324971Y361709D02*
X318593D01*
G01X343076Y32516D02*
X345670Y29922D01*
G01X343076Y54668D02*
Y32516D01*
G01X383594Y29005D02*
X388189Y24410D01*
G01X383594Y33601D02*
Y29005D01*
G01X383604Y33611D02*
X383594Y33601D01*
G01X383604Y35681D02*
Y33611D01*
G01X383594Y35691D02*
X383604Y35681D01*
G01X383594Y56698D02*
Y35691D01*
G01X350161Y37241D02*
X352756Y34646D01*
G01X350161Y60628D02*
Y37241D01*
G01X355247Y29006D02*
X359843Y24410D01*
G01X355247Y58371D02*
Y29006D01*
G01X371480Y32760D02*
Y58204D01*
G01X374016Y30224D02*
X371480Y32760D01*
G01X374016Y29922D02*
Y30224D01*
G01X357248Y32517D02*
X359843Y29922D01*
G01X357248Y61120D02*
Y32517D01*
G01X362333Y33730D02*
X366929Y29134D01*
G01X362333Y58864D02*
Y33730D01*
G01X348160D02*
X352756Y29134D01*
G01X348160Y57804D02*
Y33730D01*
G01X369420Y29006D02*
Y57435D01*
G01X374016Y24410D02*
X369420Y29006D01*
G01X364334Y37241D02*
Y59692D01*
G01X366929Y34646D02*
X364334Y37241D01*
G01X385594Y36520D02*
Y57527D01*
G01X385604Y36510D02*
X385594Y36520D01*
G01X385604Y32507D02*
Y36510D01*
G01X388189Y29922D02*
X385604Y32507D01*
G01X338944Y58800D02*
X343076Y54668D01*
G01X421043Y49930D02*
X370303Y100670D01*
G01X373054Y112170D02*
X337315D01*
G01X373055Y112171D02*
X373054Y112170D01*
G01X380513Y112171D02*
X373055D01*
G01X380514Y112170D02*
X380513Y112171D01*
G01X381958Y112170D02*
X380514D01*
G01X440256Y53872D02*
X381958Y112170D01*
G01X361863Y92574D02*
X399768Y54669D01*
G01X331722Y92574D02*
X361863D01*
G01X329722Y94574D02*
X331722Y92574D01*
G01X357718Y82574D02*
X383594Y56698D01*
G01X347989Y62800D02*
X350161Y60628D01*
G01X348818Y64800D02*
X355247Y58371D01*
G01X419043Y49101D02*
X369474Y98670D01*
G01X371480Y58204D02*
X354610Y75074D01*
G01X360205Y88574D02*
X392657Y56122D01*
G01X351568Y66800D02*
X357248Y61120D01*
G01X378855Y108171D02*
X426626Y60400D01*
G01X374713Y108171D02*
X378855D01*
G01X374712Y108170D02*
X374713Y108171D01*
G01X332213Y108170D02*
X374712D01*
G01X325876Y114507D02*
X332213Y108170D01*
G01X363425Y96670D02*
X406853Y53242D01*
G01X361034Y90574D02*
X397767Y53841D01*
G01X390657Y55293D02*
X359376Y86574D01*
G01X352269Y68928D02*
X362333Y58864D01*
G01X345164Y60800D02*
X348160Y57804D01*
G01X362692Y94574D02*
X404853Y52413D01*
G01X335722Y94574D02*
X362692D01*
G01X369420Y57435D02*
X353781Y73074D01*
G01X364334Y59692D02*
X352952Y71074D01*
G01X382786Y114171D02*
X442256Y54701D01*
G01X385594Y57527D02*
X358547Y84574D01*
G01X379684Y110171D02*
X427455Y62400D01*
G01X373884Y110171D02*
X379684D01*
G01X373883Y110170D02*
X373884Y110171D01*
G01X336486Y110170D02*
X373883D01*
G01X329940Y145173D02*
Y190286D01*
G01X347813Y127300D02*
X329940Y145173D01*
G01X476568Y127300D02*
X347813D01*
G01X348571Y132200D02*
X477326D01*
G01X333940Y146831D02*
X348571Y132200D01*
G01X333940Y191944D02*
Y146831D01*
G01X349937Y136980D02*
X478533D01*
G01X349911Y136954D02*
X349937Y136980D01*
G01X325630Y129513D02*
Y132370D01*
G01X338973Y116170D02*
X325630Y129513D01*
G01X371396Y116170D02*
X338973D01*
G01X371397Y116171D02*
X371396Y116170D01*
G01X383615Y116171D02*
X371397D01*
G01X383616Y116170D02*
X383615Y116171D01*
G01X386737Y116170D02*
X383616D01*
G01X447452Y55455D02*
X386737Y116170D01*
G01X372199Y174571D02*
X370061Y172433D01*
G01X402011Y174571D02*
X372199D01*
G01X337940Y152300D02*
Y193603D01*
G01X345518Y144722D02*
X337940Y152300D01*
G01X345518Y138570D02*
Y144722D01*
G01X349135Y134953D02*
X345518Y138570D01*
G01X477731Y134953D02*
X349135D01*
G01X374809Y172571D02*
X374616Y172378D01*
G01X400658Y172571D02*
X374809D01*
G01X385909Y118171D02*
X387565D01*
G01X385908Y118170D02*
X385909Y118171D01*
G01X384445Y118170D02*
X385908D01*
G01X384444Y118171D02*
X384445Y118170D01*
G01X370568Y118171D02*
X384444D01*
G01X370567Y118170D02*
X370568Y118171D01*
G01X341326Y118170D02*
X370567D01*
G01X333512Y125984D02*
X341326Y118170D01*
G01X333512Y127401D02*
Y125984D01*
G01X368910Y122171D02*
X390667D01*
G01X368909Y122170D02*
X368910Y122171D01*
G01X350114Y122170D02*
X368909D01*
G01X327940Y144344D02*
X350114Y122170D01*
G01X327940Y188541D02*
Y144344D01*
G01X348142Y129800D02*
X476897D01*
G01X331940Y146002D02*
X348142Y129800D01*
G01X331940Y191115D02*
Y146002D01*
G01X325876Y116703D02*
Y114507D01*
G01X325940Y143515D02*
Y187712D01*
G01X349285Y120170D02*
X325940Y143515D01*
G01X369738Y120170D02*
X349285D01*
G01X369739Y120171D02*
X369738Y120170D01*
G01X388394Y120171D02*
X369739D01*
G01X335940Y147660D02*
X342000Y141600D01*
G01X335940Y192774D02*
Y147660D01*
G01X342150Y154521D02*
Y197315D01*
G01X355691Y140980D02*
X342150Y154521D01*
G01X480191Y140980D02*
X355691D01*
G01X372226Y114171D02*
X382786D01*
G01X372225Y114170D02*
X372226Y114171D01*
G01X338144Y114170D02*
X372225D01*
G01X340150Y153692D02*
Y196486D01*
G01X354862Y138980D02*
X340150Y153692D01*
G01X479362Y138980D02*
X354862D01*
G01X357000Y143000D02*
X355500Y144500D01*
G01X481000Y143000D02*
X357000D01*
G01X371639Y216590D02*
X394229Y194000D01*
G01X365298Y216590D02*
X371639D01*
G01X351554Y230334D02*
X365298Y216590D01*
G01X351554Y236833D02*
Y230334D01*
G01X336279Y252108D02*
X351554Y236833D01*
G01X373830Y182362D02*
X372517D01*
G01X375586Y180606D02*
X373830Y182362D01*
G01X404463Y180606D02*
X375586D01*
G01X343140Y233931D02*
X328134Y248937D01*
G01X343140Y227432D02*
Y233931D01*
G01X348000Y222572D02*
X343140Y227432D01*
G01X348000Y218413D02*
Y222572D01*
G01X359218Y207195D02*
X348000Y218413D01*
G01X367872Y207195D02*
X359218D01*
G01X372517Y202550D02*
X367872Y207195D01*
G01X372517Y182362D02*
Y202550D01*
G01X371278Y178606D02*
X371124Y178760D01*
G01X403634Y178606D02*
X371278D01*
G01X349554Y236004D02*
X334279Y251279D01*
G01X349554Y229505D02*
Y236004D01*
G01X364469Y214590D02*
X349554Y229505D01*
G01X370810Y214590D02*
X364469D01*
G01X393900Y191500D02*
X370810Y214590D01*
G01X327157Y204386D02*
Y241427D01*
G01X337940Y193603D02*
X327157Y204386D01*
G01X353554Y231163D02*
Y237662D01*
G01X366127Y218590D02*
X353554Y231163D01*
G01X372810Y218590D02*
X366127D01*
G01X394900Y196500D02*
X372810Y218590D01*
G01X325157Y203557D02*
X335940Y192774D01*
G01X325157Y240598D02*
Y203557D01*
G01X368411Y210590D02*
X392501Y186500D01*
G01X359430Y210590D02*
X368411D01*
G01X350146Y219874D02*
X359430Y210590D01*
G01X350146Y223255D02*
Y219874D01*
G01X345140Y228261D02*
X350146Y223255D01*
G01X345140Y234760D02*
Y228261D01*
G01X330279Y249621D02*
X345140Y234760D01*
G01X347140Y235589D02*
X332279Y250450D01*
G01X347140Y229090D02*
Y235589D01*
G01X363640Y212590D02*
X347140Y229090D01*
G01X369240Y212590D02*
X363640D01*
G01X392830Y189000D02*
X369240Y212590D01*
G01X331157Y208308D02*
Y243085D01*
G01X342150Y197315D02*
X331157Y208308D01*
G01X375079Y176606D02*
X402805D01*
G01X374915Y176442D02*
X375079Y176606D01*
G01X376306Y182715D02*
X405327D01*
G01X329157Y207479D02*
Y242256D01*
G01X340150Y196486D02*
X329157Y207479D01*
G01X360917Y242200D02*
X392706D01*
G01X339467Y263650D02*
X360917Y242200D01*
G01X334686Y263650D02*
X339467D01*
G01X332000Y266336D02*
X334686Y263650D01*
G01X383684Y249800D02*
X405937D01*
G01X376633Y256851D02*
X383684Y249800D01*
G01X336279Y256266D02*
Y252108D01*
G01X328134Y248937D02*
Y252720D01*
G01X384052Y300583D02*
X387235Y297400D01*
G01X361746Y244200D02*
X395340D01*
G01X339896Y266050D02*
X361746Y244200D01*
G01X337500Y266050D02*
X339896D01*
G01X334279Y251279D02*
Y254850D01*
G01X338610Y298583D02*
X325893Y311300D01*
G01X349279Y298583D02*
X338610D01*
G01X349779Y298083D02*
X349279Y298583D01*
G01X349779Y296700D02*
Y298083D01*
G01X350279Y296200D02*
X349779Y296700D01*
G01X351279Y296200D02*
X350279D01*
G01X351779Y296700D02*
X351279Y296200D01*
G01X351779Y298083D02*
Y296700D01*
G01X352279Y298583D02*
X351779Y298083D01*
G01X353279Y298583D02*
X352279D01*
G01X353779Y298083D02*
X353279Y298583D01*
G01X353779Y296700D02*
Y298083D01*
G01X354279Y296200D02*
X353779Y296700D01*
G01X355279Y296200D02*
X354279D01*
G01X355779Y296700D02*
X355279Y296200D01*
G01X355779Y298083D02*
Y296700D01*
G01X356279Y298583D02*
X355779Y298083D01*
G01X357279Y298583D02*
X356279D01*
G01X357779Y298083D02*
X357279Y298583D01*
G01X357779Y296700D02*
Y298083D01*
G01X358279Y296200D02*
X357779Y296700D01*
G01X359279Y296200D02*
X358279D01*
G01X359779Y296700D02*
X359279Y296200D01*
G01X359779Y298083D02*
Y296700D01*
G01X360279Y298583D02*
X359779Y298083D01*
G01X361279Y298583D02*
X360279D01*
G01X361779Y298083D02*
X361279Y298583D01*
G01X361779Y296700D02*
Y298083D01*
G01X362279Y296200D02*
X361779Y296700D01*
G01X363279Y296200D02*
X362279D01*
G01X363779Y296700D02*
X363279Y296200D01*
G01X363779Y298083D02*
Y296700D01*
G01X364279Y298583D02*
X363779Y298083D01*
G01X365279Y298583D02*
X364279D01*
G01X365779Y298083D02*
X365279Y298583D01*
G01X365779Y296700D02*
Y298083D01*
G01X366279Y296200D02*
X365779Y296700D01*
G01X367279Y296200D02*
X366279D01*
G01X367779Y296700D02*
X367279Y296200D01*
G01X367779Y298083D02*
Y296700D01*
G01X368279Y298583D02*
X367779Y298083D01*
G01X369279Y298583D02*
X368279D01*
G01X369779Y298083D02*
X369279Y298583D01*
G01X369779Y296700D02*
Y298083D01*
G01X370279Y296200D02*
X369779Y296700D01*
G01X371279Y296200D02*
X370279D01*
G01X371779Y296700D02*
X371279Y296200D01*
G01X371779Y298083D02*
Y296700D01*
G01X372279Y298583D02*
X371779Y298083D01*
G01X382524Y298583D02*
X372279D01*
G01X387607Y293500D02*
X382524Y298583D01*
G01X358498Y240200D02*
X341998Y256700D01*
G01X390584Y240200D02*
X358498D01*
G01X373882Y246482D02*
X401381D01*
G01X358096Y262268D02*
X373882Y246482D01*
G01X355845Y238200D02*
X389329D01*
G01X340280Y253765D02*
X355845Y238200D01*
G01X383630Y289400D02*
X387530Y285500D01*
G01X379007Y289400D02*
X383630D01*
G01X378507Y288900D02*
X379007Y289400D01*
G01X378507Y286000D02*
Y288900D01*
G01X378007Y285500D02*
X378507Y286000D01*
G01X377007Y285500D02*
X378007D01*
G01X376507Y286000D02*
X377007Y285500D01*
G01X376507Y288900D02*
Y286000D01*
G01X376007Y289400D02*
X376507Y288900D01*
G01X375007Y289400D02*
X376007D01*
G01X374507Y288900D02*
X375007Y289400D01*
G01X374507Y286000D02*
Y288900D01*
G01X374007Y285500D02*
X374507Y286000D01*
G01X373007Y285500D02*
X374007D01*
G01X372507Y286000D02*
X373007Y285500D01*
G01X372507Y288900D02*
Y286000D01*
G01X372007Y289400D02*
X372507Y288900D01*
G01X371007Y289400D02*
X372007D01*
G01X370507Y288900D02*
X371007Y289400D01*
G01X370507Y286000D02*
Y288900D01*
G01X370007Y285500D02*
X370507Y286000D01*
G01X369007Y285500D02*
X370007D01*
G01X368507Y286000D02*
X369007Y285500D01*
G01X368507Y288900D02*
Y286000D01*
G01X368007Y289400D02*
X368507Y288900D01*
G01X363918Y289400D02*
X368007D01*
G01X363418Y288900D02*
X363918Y289400D01*
G01X363418Y286200D02*
Y288900D01*
G01X362918Y285700D02*
X363418Y286200D01*
G01X361918Y285700D02*
X362918D01*
G01X361418Y286200D02*
X361918Y285700D01*
G01X361418Y288900D02*
Y286200D01*
G01X360918Y289400D02*
X361418Y288900D01*
G01X359918Y289400D02*
X360918D01*
G01X359418Y288900D02*
X359918Y289400D01*
G01X359418Y286200D02*
Y288900D01*
G01X358918Y285700D02*
X359418Y286200D01*
G01X357918Y285700D02*
X358918D01*
G01X354356Y289262D02*
X357918Y285700D01*
G01X342273Y289262D02*
X354356D01*
G01X327656Y303879D02*
X342273Y289262D01*
G01X338279Y252937D02*
Y257095D01*
G01X353554Y237662D02*
X338279Y252937D01*
G01X350938Y283262D02*
X330438D01*
G01X358400Y275800D02*
X350938Y283262D01*
G01X371433Y275800D02*
X358400D01*
G01X371933Y276300D02*
X371433Y275800D01*
G01X371933Y278500D02*
Y276300D01*
G01X372433Y279000D02*
X371933Y278500D01*
G01X373433Y279000D02*
X372433D01*
G01X373933Y278500D02*
X373433Y279000D01*
G01X373933Y276300D02*
Y278500D01*
G01X374433Y275800D02*
X373933Y276300D01*
G01X375433Y275800D02*
X374433D01*
G01X375933Y276300D02*
X375433Y275800D01*
G01X375933Y278500D02*
Y276300D01*
G01X376433Y279000D02*
X375933Y278500D01*
G01X377433Y279000D02*
X376433D01*
G01X377933Y278500D02*
X377433Y279000D01*
G01X377933Y276300D02*
Y278500D01*
G01X378433Y275800D02*
X377933Y276300D01*
G01X379433Y275800D02*
X378433D01*
G01X379933Y276300D02*
X379433Y275800D01*
G01X379933Y278500D02*
Y276300D01*
G01X380433Y279000D02*
X379933Y278500D01*
G01X381433Y279000D02*
X380433D01*
G01X381933Y278500D02*
X381433Y279000D01*
G01X381933Y276300D02*
Y278500D01*
G01X382433Y275800D02*
X381933Y276300D01*
G01X387000Y275800D02*
X382433D01*
G01X383976Y254200D02*
X376633Y261543D01*
G01X405474Y254200D02*
X383976D01*
G01X330279Y253192D02*
Y249621D01*
G01X326298Y257173D02*
X330279Y253192D01*
G01X332279Y250450D02*
Y254021D01*
G01X383901Y294050D02*
X388351Y289600D01*
G01X381786Y294050D02*
X383901D01*
G01X381286Y293550D02*
X381786Y294050D01*
G01X381286Y291900D02*
Y293550D01*
G01X380786Y291400D02*
X381286Y291900D01*
G01X379786Y291400D02*
X380786D01*
G01X379286Y291900D02*
X379786Y291400D01*
G01X379286Y295200D02*
Y291900D01*
G01X378786Y295700D02*
X379286Y295200D01*
G01X377786Y295700D02*
X378786D01*
G01X377286Y295200D02*
X377786Y295700D01*
G01X377286Y291900D02*
Y295200D01*
G01X376786Y291400D02*
X377286Y291900D01*
G01X375786Y291400D02*
X376786D01*
G01X375286Y291900D02*
X375786Y291400D01*
G01X375286Y295200D02*
Y291900D01*
G01X374786Y295700D02*
X375286Y295200D01*
G01X373786Y295700D02*
X374786D01*
G01X373286Y295200D02*
X373786Y295700D01*
G01X373286Y291900D02*
Y295200D01*
G01X372786Y291400D02*
X373286Y291900D01*
G01X371786Y291400D02*
X372786D01*
G01X371286Y291900D02*
X371786Y291400D01*
G01X371286Y293550D02*
Y291900D01*
G01X370786Y294050D02*
X371286Y293550D01*
G01X369786Y294050D02*
X370786D01*
G01X369286Y293550D02*
X369786Y294050D01*
G01X369286Y291900D02*
Y293550D01*
G01X368786Y291400D02*
X369286Y291900D01*
G01X367786Y291400D02*
X368786D01*
G01X367286Y291900D02*
X367786Y291400D01*
G01X367286Y293550D02*
Y291900D01*
G01X366786Y294050D02*
X367286Y293550D01*
G01X365786Y294050D02*
X366786D01*
G01X365286Y293550D02*
X365786Y294050D01*
G01X365286Y291900D02*
Y293550D01*
G01X364786Y291400D02*
X365286Y291900D01*
G01X363786Y291400D02*
X364786D01*
G01X363286Y291900D02*
X363786Y291400D01*
G01X363286Y293550D02*
Y291900D01*
G01X362786Y294050D02*
X363286Y293550D01*
G01X361786Y294050D02*
X362786D01*
G01X361286Y293550D02*
X361786Y294050D01*
G01X361286Y291900D02*
Y293550D01*
G01X360786Y291400D02*
X361286Y291900D01*
G01X359786Y291400D02*
X360786D01*
G01X359286Y291900D02*
X359786Y291400D01*
G01X359286Y293550D02*
Y291900D01*
G01X358786Y294050D02*
X359286Y293550D01*
G01X357786Y294050D02*
X358786D01*
G01X357286Y293550D02*
X357786Y294050D01*
G01X357286Y291900D02*
Y293550D01*
G01X356786Y291400D02*
X357286Y291900D01*
G01X355786Y291400D02*
X356786D01*
G01X355286Y291900D02*
X355786Y291400D01*
G01X355286Y293550D02*
Y291900D01*
G01X354786Y294050D02*
X355286Y293550D01*
G01X353786Y294050D02*
X354786D01*
G01X353286Y293550D02*
X353786Y294050D01*
G01X353286Y291900D02*
Y293550D01*
G01X352786Y291400D02*
X353286Y291900D01*
G01X351786Y291400D02*
X352786D01*
G01X351286Y291900D02*
X351786Y291400D01*
G01X351286Y293550D02*
Y291900D01*
G01X350786Y294050D02*
X351286Y293550D01*
G01X344366Y294050D02*
X350786D01*
G01X343866Y294550D02*
X344366Y294050D01*
G01X343866Y296000D02*
Y294550D01*
G01X343366Y296500D02*
X343866Y296000D01*
G01X342366Y296500D02*
X343366D01*
G01X341866Y296000D02*
X342366Y296500D01*
G01X341866Y294550D02*
Y296000D01*
G01X341366Y294050D02*
X341866Y294550D01*
G01X340314Y294050D02*
X341366D01*
G01X331026Y303338D02*
X340314Y294050D01*
G01X325676Y299424D02*
Y300132D01*
G01X326383Y298717D02*
X325676Y299424D01*
G01X327091Y298717D02*
X326383D01*
G01X327983Y299609D02*
X327091Y298717D01*
G01X329398Y298902D02*
X328691Y299609D01*
G01X329398Y298194D02*
Y298902D01*
G01X328506Y297302D02*
X329398Y298194D01*
G01X328506Y296594D02*
Y297302D01*
G01X329213Y295887D02*
X328506Y296594D01*
G01X329921Y295887D02*
X329213D01*
G01X330813Y296779D02*
X329921Y295887D01*
G01X331521Y296779D02*
X330813D01*
G01X332228Y296072D02*
X331521Y296779D01*
G01X332228Y295364D02*
Y296072D01*
G01X331336Y294472D02*
X332228Y295364D01*
G01X331336Y293764D02*
Y294472D01*
G01X337838Y287262D02*
X331336Y293764D01*
G01X352638Y287262D02*
X337838D01*
G01X356622Y283278D02*
X352638Y287262D01*
G01X386922Y283278D02*
X356622D01*
G01X388500Y281700D02*
X386922Y283278D01*
G01X381011Y269700D02*
X413596D01*
G01X368610Y257299D02*
X381011Y269700D01*
G01X351809Y285262D02*
X336738D01*
G01X359093Y277978D02*
X351809Y285262D01*
G01X360621Y277978D02*
X359093D01*
G01X361121Y278478D02*
X360621Y277978D01*
G01X361121Y280600D02*
Y278478D01*
G01X361621Y281100D02*
X361121Y280600D01*
G01X362621Y281100D02*
X361621D01*
G01X363121Y280600D02*
X362621Y281100D01*
G01X363121Y278478D02*
Y280600D01*
G01X363621Y277978D02*
X363121Y278478D01*
G01X364621Y277978D02*
X363621D01*
G01X365121Y278478D02*
X364621Y277978D01*
G01X365121Y280600D02*
Y278478D01*
G01X365621Y281100D02*
X365121Y280600D01*
G01X366621Y281100D02*
X365621D01*
G01X367121Y280600D02*
X366621Y281100D01*
G01X367121Y278478D02*
Y280600D01*
G01X367621Y277978D02*
X367121Y278478D01*
G01X368621Y277978D02*
X367621D01*
G01X369121Y278478D02*
X368621Y277978D01*
G01X369121Y280600D02*
Y278478D01*
G01X369621Y281100D02*
X369121Y280600D01*
G01X385478Y281100D02*
X369621D01*
G01X388725Y277853D02*
X385478Y281100D01*
G01X326500Y329400D02*
X325300Y330600D01*
G01X338900Y329400D02*
X326500D01*
G01X346328Y321972D02*
X338900Y329400D01*
G01X351300Y321972D02*
X346328D01*
G01X351800Y322472D02*
X351300Y321972D01*
G01X351800Y323600D02*
Y322472D01*
G01X352300Y324100D02*
X351800Y323600D01*
G01X353300Y324100D02*
X352300D01*
G01X353800Y323600D02*
X353300Y324100D01*
G01X353800Y322472D02*
Y323600D01*
G01X354300Y321972D02*
X353800Y322472D01*
G01X355300Y321972D02*
X354300D01*
G01X355800Y322472D02*
X355300Y321972D01*
G01X355800Y323600D02*
Y322472D01*
G01X356300Y324100D02*
X355800Y323600D01*
G01X357300Y324100D02*
X356300D01*
G01X357800Y323600D02*
X357300Y324100D01*
G01X357800Y322472D02*
Y323600D01*
G01X358300Y321972D02*
X357800Y322472D01*
G01X369572Y321972D02*
X358300D01*
G01X371700Y324100D02*
X369572Y321972D01*
G01X384650Y324100D02*
X371700D01*
G01X389128Y328578D02*
X384650Y324100D01*
G01X335973Y351773D02*
X433644D01*
G01X330000Y345800D02*
X335973Y351773D01*
G01X339439Y300583D02*
X384052D01*
G01X326077Y313945D02*
X339439Y300583D01*
G01X335381Y353719D02*
X334881D01*
G01X335435Y353773D02*
X335381Y353719D01*
G01X437681Y353773D02*
X335435D01*
G01X386561Y321139D02*
X427053D01*
G01X385022Y319600D02*
X386561Y321139D01*
G01X385022Y318600D02*
Y319600D01*
G01X384522Y318100D02*
X385022Y318600D01*
G01X383522Y318100D02*
X384522D01*
G01X383022Y318600D02*
X383522Y318100D01*
G01X383022Y319600D02*
Y318600D01*
G01X382522Y320100D02*
X383022Y319600D01*
G01X381522Y320100D02*
X382522D01*
G01X381022Y319600D02*
X381522Y320100D01*
G01X381022Y318600D02*
Y319600D01*
G01X380522Y318100D02*
X381022Y318600D01*
G01X379522Y318100D02*
X380522D01*
G01X379022Y318600D02*
X379522Y318100D01*
G01X379022Y319600D02*
Y318600D01*
G01X378522Y320100D02*
X379022Y319600D01*
G01X377522Y320100D02*
X378522D01*
G01X377022Y319600D02*
X377522Y320100D01*
G01X377022Y318600D02*
Y319600D01*
G01X376522Y318100D02*
X377022Y318600D01*
G01X375522Y318100D02*
X376522D01*
G01X375022Y318600D02*
X375522Y318100D01*
G01X375022Y319600D02*
Y318600D01*
G01X374522Y320100D02*
X375022Y319600D01*
G01X373522Y320100D02*
X374522D01*
G01X373022Y319600D02*
X373522Y320100D01*
G01X373022Y318472D02*
Y319600D01*
G01X372522Y317972D02*
X373022Y318472D01*
G01X344528Y317972D02*
X372522D01*
G01X337100Y325400D02*
X344528Y317972D01*
G01X325500Y325400D02*
X337100D01*
G01X339927Y343773D02*
X339000Y344700D01*
G01X345053Y343773D02*
X339927D01*
G01X347626Y341200D02*
X345053Y343773D01*
G01X407770Y341200D02*
X347626D01*
G01X330901Y361981D02*
X326629Y357709D01*
G01X331730Y359981D02*
X327458Y355709D01*
G01X444302Y359981D02*
X331730D01*
G01X348455Y343200D02*
X430731D01*
G01X345882Y345773D02*
X348455Y343200D01*
G01X341427Y345773D02*
X345882D01*
G01X340440Y346760D02*
X341427Y345773D01*
G01X334095Y346760D02*
X340440D01*
G01X331108Y343773D02*
X334095Y346760D01*
G01X328590Y343773D02*
X331108D01*
G01X327417Y342600D02*
X328590Y343773D01*
G01X327400Y342600D02*
X327417D01*
G01X327656Y304258D02*
Y303879D01*
G01X341791Y317808D02*
X336199Y323400D01*
G01X341791Y315192D02*
Y317808D01*
G01X343256Y313727D02*
X341791Y315192D01*
G01X349675Y313727D02*
X343256D01*
G01X350175Y314227D02*
X349675Y313727D01*
G01X350175Y315000D02*
Y314227D01*
G01X350675Y315500D02*
X350175Y315000D01*
G01X351675Y315500D02*
X350675D01*
G01X352175Y315000D02*
X351675Y315500D01*
G01X352175Y314227D02*
Y315000D01*
G01X352675Y313727D02*
X352175Y314227D01*
G01X364227Y313727D02*
X352675D01*
G01X366472Y315972D02*
X364227Y313727D01*
G01X371155Y315972D02*
X366472D01*
G01X373400Y313727D02*
X371155Y315972D01*
G01X375627Y313727D02*
X373400D01*
G01X377900Y316000D02*
X375627Y313727D01*
G01X380927Y316000D02*
X377900D01*
G01X383200Y313727D02*
X380927Y316000D01*
G01X385827Y313727D02*
X383200D01*
G01X388900Y316800D02*
X385827Y313727D01*
G01X386505Y347200D02*
X387005Y347700D01*
G01X385505Y347200D02*
X386505D01*
G01X385005Y347700D02*
X385505Y347200D01*
G01X385005Y349273D02*
Y347700D01*
G01X384505Y349773D02*
X385005Y349273D01*
G01X379747Y349773D02*
X384505D01*
G01X379247Y349273D02*
X379747Y349773D01*
G01X379247Y347800D02*
Y349273D01*
G01X378747Y347300D02*
X379247Y347800D01*
G01X377747Y347300D02*
X378747D01*
G01X377247Y347800D02*
X377747Y347300D01*
G01X377247Y349273D02*
Y347800D01*
G01X376747Y349773D02*
X377247Y349273D01*
G01X367838Y349773D02*
X376747D01*
G01X367338Y349273D02*
X367838Y349773D01*
G01X367338Y347700D02*
Y349273D01*
G01X366838Y347200D02*
X367338Y347700D01*
G01X365838Y347200D02*
X366838D01*
G01X365338Y347700D02*
X365838Y347200D01*
G01X365338Y349273D02*
Y347700D01*
G01X364838Y349773D02*
X365338Y349273D01*
G01X363838Y349773D02*
X364838D01*
G01X363338Y349273D02*
X363838Y349773D01*
G01X363338Y347700D02*
Y349273D01*
G01X362838Y347200D02*
X363338Y347700D01*
G01X361838Y347200D02*
X362838D01*
G01X361338Y347700D02*
X361838Y347200D01*
G01X361338Y349273D02*
Y347700D01*
G01X360838Y349773D02*
X361338Y349273D01*
G01X356659Y349773D02*
X360838D01*
G01X356159Y349273D02*
X356659Y349773D01*
G01X356159Y347700D02*
Y349273D01*
G01X355659Y347200D02*
X356159Y347700D01*
G01X354659Y347200D02*
X355659D01*
G01X354159Y347700D02*
X354659Y347200D01*
G01X354159Y349273D02*
Y347700D01*
G01X353659Y349773D02*
X354159Y349273D01*
G01X352659Y349773D02*
X353659D01*
G01X352159Y349273D02*
X352659Y349773D01*
G01X352159Y347700D02*
Y349273D01*
G01X351659Y347200D02*
X352159Y347700D01*
G01X350659Y347200D02*
X351659D01*
G01X350159Y347700D02*
X350659Y347200D01*
G01X350159Y349273D02*
Y347700D01*
G01X349659Y349773D02*
X350159Y349273D01*
G01X345700Y349773D02*
X349659D01*
G01X347032Y330478D02*
X342028Y335482D01*
G01X385282Y330478D02*
X347032D01*
G01X386382Y331578D02*
X385282Y330478D01*
G01X425581Y331578D02*
X386382D01*
G01X340151Y302700D02*
X326906Y315945D01*
G01X342900Y302700D02*
X340151D01*
G01X345000Y304800D02*
X342900Y302700D01*
G01X347874Y304800D02*
X345000D01*
G01X350091Y302583D02*
X347874Y304800D01*
G01X374383Y302583D02*
X350091D01*
G01X377274Y305474D02*
X374383Y302583D01*
G01X382428Y305474D02*
X377274D01*
G01X386908Y300994D02*
X382428Y305474D01*
G01X386642Y311727D02*
X387691Y312776D01*
G01X381299Y311727D02*
X386642D01*
G01X380699Y312327D02*
X381299Y311727D01*
G01X380699Y313500D02*
Y312327D01*
G01X380199Y314000D02*
X380699Y313500D01*
G01X379199Y314000D02*
X380199D01*
G01X378699Y313500D02*
X379199Y314000D01*
G01X378699Y312327D02*
Y313500D01*
G01X378099Y311727D02*
X378699Y312327D01*
G01X370016Y311727D02*
X378099D01*
G01X369516Y312227D02*
X370016Y311727D01*
G01X369516Y313400D02*
Y312227D01*
G01X369016Y313900D02*
X369516Y313400D01*
G01X368016Y313900D02*
X369016D01*
G01X367516Y313400D02*
X368016Y313900D01*
G01X367516Y312227D02*
Y313400D01*
G01X367016Y311727D02*
X367516Y312227D01*
G01X342427Y311727D02*
X367016D01*
G01X338343Y315811D02*
X342427Y311727D01*
G01X338343Y316619D02*
Y315811D01*
G01X338858Y317134D02*
X338343Y316619D01*
G01X338858Y317842D02*
Y317134D01*
G01X338151Y318549D02*
X338858Y317842D01*
G01X337443Y318549D02*
X338151D01*
G01X335851Y316957D02*
X337443Y318549D01*
G01X335143Y316957D02*
X335851D01*
G01X334436Y317664D02*
X335143Y316957D01*
G01X334436Y318372D02*
Y317664D01*
G01X336028Y319964D02*
X334436Y318372D01*
G01X336028Y320672D02*
Y319964D01*
G01X335321Y321379D02*
X336028Y320672D01*
G01X334613Y321379D02*
X335321D01*
G01X333434Y320200D02*
X334613Y321379D01*
G01X332164Y320200D02*
X333434D01*
G01X330964Y321400D02*
X332164Y320200D01*
G01X325500Y321400D02*
X330964D01*
G01X349469Y345200D02*
X431700D01*
G01X346896Y347773D02*
X349469Y345200D01*
G01X342627Y347773D02*
X346896D01*
G01X340800Y349600D02*
X342627Y347773D01*
G01X337600Y349600D02*
X340800D01*
G01X334073Y355773D02*
X326300Y348000D01*
G01X438510Y355773D02*
X334073D01*
G01X335773Y337773D02*
X335400Y337400D01*
G01X342566Y337773D02*
X335773D01*
G01X347761Y332578D02*
X342566Y337773D01*
G01X425996Y332578D02*
X347761D01*
G01X386159Y337080D02*
X388705Y334534D01*
G01X384413Y335334D02*
X386159Y337080D01*
G01X347834Y335334D02*
X384413D01*
G01X343395Y339773D02*
X347834Y335334D01*
G01X330248Y339773D02*
X343395D01*
G01X328802Y338327D02*
X330248Y339773D01*
G01X385389Y322100D02*
X388059Y324770D01*
G01X372529Y322100D02*
X385389D01*
G01X370401Y319972D02*
X372529Y322100D01*
G01X345428Y319972D02*
X370401D01*
G01X338000Y327400D02*
X345428Y319972D01*
G01X331026Y303354D02*
Y303338D01*
G01X346475Y328206D02*
X341199Y333482D01*
G01X384425Y328206D02*
X346475D01*
G01X386797Y330578D02*
X384425Y328206D01*
G01X425166Y330578D02*
X386797D01*
G01X346797Y339200D02*
X403000D01*
G01X344224Y341773D02*
X346797Y339200D01*
G01X336624Y341773D02*
X344224D01*
G01X336124Y342273D02*
X336624Y341773D01*
G01X336124Y343800D02*
Y342273D01*
G01X335624Y344300D02*
X336124Y343800D01*
G01X334624Y344300D02*
X335624D01*
G01X334124Y343800D02*
X334624Y344300D01*
G01X334124Y342273D02*
Y343800D01*
G01X333624Y341773D02*
X334124Y342273D01*
G01X329419Y341773D02*
X333624D01*
G01X327973Y340327D02*
X329419Y341773D01*
G01X330072Y363981D02*
X325800Y359709D01*
G01X334639Y311673D02*
X329364Y316949D01*
G01X336649Y311673D02*
X334639D01*
G01X340843Y307479D02*
X336649Y311673D01*
G01X340843Y305500D02*
Y307479D01*
G01X341343Y305000D02*
X340843Y305500D01*
G01X342343Y305000D02*
X341343D01*
G01X342843Y305500D02*
X342343Y305000D01*
G01X342843Y306974D02*
Y305500D01*
G01X343343Y307474D02*
X342843Y306974D01*
G01X351268Y307474D02*
X343343D01*
G01X351768Y306974D02*
X351268Y307474D01*
G01X351768Y305100D02*
Y306974D01*
G01X352268Y304600D02*
X351768Y305100D01*
G01X353268Y304600D02*
X352268D01*
G01X353768Y305100D02*
X353268Y304600D01*
G01X353768Y306974D02*
Y305100D01*
G01X354268Y307474D02*
X353768Y306974D01*
G01X355268Y307474D02*
X354268D01*
G01X355768Y306974D02*
X355268Y307474D01*
G01X355768Y305100D02*
Y306974D01*
G01X356268Y304600D02*
X355768Y305100D01*
G01X357268Y304600D02*
X356268D01*
G01X357768Y305100D02*
X357268Y304600D01*
G01X357768Y306974D02*
Y305100D01*
G01X358268Y307474D02*
X357768Y306974D01*
G01X359268Y307474D02*
X358268D01*
G01X359768Y306974D02*
X359268Y307474D01*
G01X359768Y305100D02*
Y306974D01*
G01X360268Y304600D02*
X359768Y305100D01*
G01X361268Y304600D02*
X360268D01*
G01X361768Y305100D02*
X361268Y304600D01*
G01X361768Y306974D02*
Y305100D01*
G01X362268Y307474D02*
X361768Y306974D01*
G01X363268Y307474D02*
X362268D01*
G01X363768Y306974D02*
X363268Y307474D01*
G01X363768Y305100D02*
Y306974D01*
G01X364268Y304600D02*
X363768Y305100D01*
G01X365268Y304600D02*
X364268D01*
G01X365768Y305100D02*
X365268Y304600D01*
G01X365768Y306974D02*
Y305100D01*
G01X366268Y307474D02*
X365768Y306974D01*
G01X367268Y307474D02*
X366268D01*
G01X367768Y306974D02*
X367268Y307474D01*
G01X367768Y305100D02*
Y306974D01*
G01X368268Y304600D02*
X367768Y305100D01*
G01X369268Y304600D02*
X368268D01*
G01X369768Y305100D02*
X369268Y304600D01*
G01X369768Y306974D02*
Y305100D01*
G01X370268Y307474D02*
X369768Y306974D01*
G01X371268Y307474D02*
X370268D01*
G01X371768Y306974D02*
X371268Y307474D01*
G01X371768Y305100D02*
Y306974D01*
G01X372268Y304600D02*
X371768Y305100D01*
G01X373268Y304600D02*
X372268D01*
G01X373768Y305100D02*
X373268Y304600D01*
G01X373768Y306974D02*
Y305100D01*
G01X374268Y307474D02*
X373768Y306974D01*
G01X386805Y307474D02*
X374268D01*
G01X389279Y305000D02*
X386805Y307474D01*
G01X325861Y302439D02*
X325153D01*
G01X326568Y301732D02*
X325861Y302439D01*
G01X326568Y301024D02*
Y301732D01*
G01X325676Y300132D02*
X326568Y301024D01*
G01X328691Y299609D02*
X327983D01*
G01X384546Y326206D02*
X387918Y329578D01*
G01X369511Y326206D02*
X384546D01*
G01X369011Y325706D02*
X369511Y326206D01*
G01X369011Y324500D02*
Y325706D01*
G01X368511Y324000D02*
X369011Y324500D01*
G01X367511Y324000D02*
X368511D01*
G01X367011Y324500D02*
X367511Y324000D01*
G01X367011Y325706D02*
Y324500D01*
G01X366511Y326206D02*
X367011Y325706D01*
G01X365511Y326206D02*
X366511D01*
G01X365011Y325706D02*
X365511Y326206D01*
G01X365011Y324500D02*
Y325706D01*
G01X364511Y324000D02*
X365011Y324500D01*
G01X363511Y324000D02*
X364511D01*
G01X363011Y324500D02*
X363511Y324000D01*
G01X363011Y325706D02*
Y324500D01*
G01X362511Y326206D02*
X363011Y325706D01*
G01X345087Y326206D02*
X362511D01*
G01X339811Y331482D02*
X345087Y326206D01*
G01X328282Y331482D02*
X339811D01*
G01X328100Y331300D02*
X328282Y331482D01*
G01X335471Y313673D02*
X329785Y319359D01*
G01X337527Y313673D02*
X335471D01*
G01X341726Y309474D02*
X337527Y313673D01*
G01X380829Y309474D02*
X341726D01*
G01X381003Y309300D02*
X380829Y309474D01*
G01X429999Y309300D02*
X381003D01*
G01X329243Y365981D02*
X324971Y361709D01*
G01X325144Y353200D02*
Y350500D01*
G01X325644Y353700D02*
X325144Y353200D01*
G01X329171Y353700D02*
X325644D01*
G01X333452Y357981D02*
X329171Y353700D01*
G01X443473Y357981D02*
X333452D01*
G01X354519Y385981D02*
X468847D01*
G01X352000Y388500D02*
X354519Y385981D01*
G01X344000Y388500D02*
X352000D01*
G01X350704Y377981D02*
X457960D01*
G01X349135Y379550D02*
X350704Y377981D01*
G01X326749Y379550D02*
X349135D01*
G01X326249Y380050D02*
X326749Y379550D01*
G01X326249Y381056D02*
Y380050D01*
G01X325749Y381556D02*
X326249Y381056D01*
G01X352362Y381981D02*
X463769D01*
G01X350793Y383550D02*
X352362Y381981D01*
G01X330520Y383550D02*
X350793D01*
G01X329058Y385012D02*
X330520Y383550D01*
G01X329058Y387930D02*
Y385012D01*
G01X328558Y388430D02*
X329058Y387930D01*
G01X327558Y388430D02*
X328558D01*
G01X327058Y387930D02*
X327558Y388430D01*
G01X327058Y386133D02*
Y387930D01*
G01X326558Y385633D02*
X327058Y386133D01*
G01X325558Y385633D02*
X326558D01*
G01X325058Y386133D02*
X325558Y385633D01*
G01X325058Y387930D02*
Y386133D01*
G01X445131Y361981D02*
X330901D01*
G01X332386Y385914D02*
X331765Y386535D01*
G01X333568Y385914D02*
X332386D01*
G01X334068Y386414D02*
X333568Y385914D01*
G01X334068Y388000D02*
Y386414D01*
G01X334568Y388500D02*
X334068Y388000D01*
G01X335568Y388500D02*
X334568D01*
G01X336068Y388000D02*
X335568Y388500D01*
G01X336068Y386414D02*
Y388000D01*
G01X336568Y385914D02*
X336068Y386414D01*
G01X337747Y385914D02*
X336568D01*
G01X338247Y386414D02*
X337747Y385914D01*
G01X338247Y388000D02*
Y386414D01*
G01X338747Y388500D02*
X338247Y388000D01*
G01X339747Y388500D02*
X338747D01*
G01X340247Y388000D02*
X339747Y388500D01*
G01X340247Y386414D02*
Y388000D01*
G01X340747Y385914D02*
X340247Y386414D01*
G01X351258Y385914D02*
X340747D01*
G01X353191Y383981D02*
X351258Y385914D01*
G01X466856Y383981D02*
X353191D01*
G01X332161Y399596D02*
X337592Y405027D01*
G01X351533Y379981D02*
X462940D01*
G01X349964Y381550D02*
X351533Y379981D01*
G01X329691Y381550D02*
X349964D01*
G01X327608Y383633D02*
X329691Y381550D01*
G01X347388Y369981D02*
X448725D01*
G01X345819Y371550D02*
X347388Y369981D01*
G01X337956Y371550D02*
X345819D01*
G01X337006Y370600D02*
X337956Y371550D01*
G01X337006Y368500D02*
Y370600D01*
G01X336506Y368000D02*
X337006Y368500D01*
G01X335506Y368000D02*
X336506D01*
G01X335006Y368500D02*
X335506Y368000D01*
G01X335006Y370800D02*
Y368500D01*
G01X334506Y371300D02*
X335006Y370800D01*
G01X333506Y371300D02*
X334506D01*
G01X333006Y370800D02*
X333506Y371300D01*
G01X333006Y368500D02*
Y370800D01*
G01X332506Y368000D02*
X333006Y368500D01*
G01X331406Y368000D02*
X332506D01*
G01X330906Y368500D02*
X331406Y368000D01*
G01X330906Y370950D02*
Y368500D01*
G01X330406Y371450D02*
X330906Y370950D01*
G01X329250Y371450D02*
X330406D01*
G01X325124Y367324D02*
X329250Y371450D01*
G01X348306Y377550D02*
X326463D01*
G01X349875Y375981D02*
X348306Y377550D01*
G01X456698Y375981D02*
X349875D01*
G01X347477Y375550D02*
X327292D01*
G01X349046Y373981D02*
X347477Y375550D01*
G01X450383Y373981D02*
X349046D01*
G01X355519Y387981D02*
X475336D01*
G01X353000Y390500D02*
X355519Y387981D01*
G01X340412Y365981D02*
X447067D01*
G01X340375Y365944D02*
X340412Y365981D01*
G01X348217Y371981D02*
X449554D01*
G01X346648Y373550D02*
X348217Y371981D01*
G01X328121Y373550D02*
X346648D01*
G01X445960Y363981D02*
X330072D01*
G01X337481Y365981D02*
X329243D01*
G01X339481Y367981D02*
X337481Y365981D01*
G01X447896Y367981D02*
X339481D01*
G01X421043Y28917D02*
Y49930D01*
G01X416536Y24410D02*
X421043Y28917D01*
G01X440256Y37106D02*
Y53872D01*
G01X437796Y34646D02*
X440256Y37106D01*
G01X399767Y32518D02*
X402363Y29922D01*
G01X399767Y53012D02*
Y32518D01*
G01X447452Y32492D02*
Y55455D01*
G01X444882Y29922D02*
X447452Y32492D01*
G01X419043Y32429D02*
Y49101D01*
G01X416536Y29922D02*
X419043Y32429D01*
G01X392657Y37265D02*
X395276Y34646D01*
G01X392657Y56122D02*
Y37265D01*
G01X449452Y28980D02*
X444882Y24410D01*
G01X433160Y32373D02*
X430709Y29922D01*
G01X433160Y38294D02*
Y32373D01*
G01X433169Y38340D02*
X433160Y38294D01*
G01X433169Y44199D02*
Y38340D01*
G01X433168Y44348D02*
X433169Y44199D01*
G01X433160Y44388D02*
X433168Y44348D01*
G01X433160Y53866D02*
Y44388D01*
G01X406853Y37242D02*
X409449Y34646D01*
G01X406853Y53242D02*
Y37242D01*
G01X397767Y29006D02*
X402363Y24410D01*
G01X397767Y53841D02*
Y29006D01*
G01X390657Y33753D02*
Y55293D01*
G01X395276Y29134D02*
X390657Y33753D01*
G01X404853Y33730D02*
X409449Y29134D01*
G01X404853Y52413D02*
Y33730D01*
G01X442256Y33594D02*
X437796Y29134D01*
G01X442256Y54701D02*
Y33594D01*
G01X435160Y28861D02*
X430709Y24410D01*
G01X435160Y38100D02*
Y28861D01*
G01X435169Y38146D02*
X435160Y38100D01*
G01X435169Y44206D02*
Y38146D01*
G01X435167Y44553D02*
X435169Y44206D01*
G01X435160Y44587D02*
X435167Y44553D01*
G01X435160Y53037D02*
Y44587D01*
G01X399768Y53013D02*
X399767Y53012D01*
G01X399768Y54669D02*
Y53013D01*
G01X387565Y118171D02*
X449452Y56284D01*
G01X390667Y122171D02*
X456429Y56409D01*
G01X430872Y56154D02*
X433160Y53866D01*
G01X430872Y56155D02*
Y56154D01*
G01X426627Y60400D02*
X430872Y56155D01*
G01X426626Y60400D02*
X426627D01*
G01X454429Y55580D02*
X389839Y120170D01*
G01X435161Y53038D02*
X435160Y53037D01*
G01X435161Y54694D02*
Y53038D01*
G01X432872Y56983D02*
X435161Y54694D01*
G01X432872Y56984D02*
Y56983D01*
G01X427456Y62400D02*
X432872Y56984D01*
G01X427455Y62400D02*
X427456D01*
G01X433672Y167499D02*
X485684D01*
G01X407171Y194000D02*
X433672Y167499D01*
G01X427811Y157258D02*
X404463Y180606D01*
G01X481780Y157258D02*
X427811D01*
G01X427897Y154343D02*
X403634Y178606D01*
G01X481866Y154343D02*
X427897D01*
G01X431030Y165499D02*
X405029Y191500D01*
G01X484855Y165499D02*
X431030D01*
G01X427562Y149020D02*
X402011Y174571D01*
G01X481531Y149020D02*
X427562D01*
G01X427378Y145851D02*
X400658Y172571D01*
G01X481871Y145851D02*
X427378D01*
G01X437172Y169499D02*
X410171Y196500D01*
G01X486513Y169499D02*
X437172D01*
G01X388395Y120170D02*
X388394Y120171D01*
G01X389839Y120170D02*
X388395D01*
G01X429372Y161499D02*
X483197D01*
G01X404371Y186500D02*
X429372Y161499D01*
G01X430201Y163499D02*
X404700Y189000D01*
G01X484026Y163499D02*
X430201D01*
G01X427856Y151555D02*
X481825D01*
G01X402805Y176606D02*
X427856Y151555D01*
G01X428543Y159499D02*
X482368D01*
G01X405327Y182715D02*
X428543Y159499D01*
G01X399829Y234030D02*
X401575Y232284D01*
G01X399829Y236223D02*
Y234030D01*
G01X397452Y238600D02*
X399829Y236223D01*
G01X394229Y194000D02*
X407171D01*
G01X403700Y234096D02*
X405512Y232284D01*
G01X403700Y240226D02*
Y234096D01*
G01X405029Y191500D02*
X393900D01*
G01X396384Y234400D02*
X390584Y240200D01*
G01X397715Y234400D02*
X396384D01*
G01X399500Y232615D02*
X397715Y234400D01*
G01X399500Y232166D02*
Y232615D01*
G01X401475Y230191D02*
X399500Y232166D01*
G01X403668Y230191D02*
X401475D01*
G01X405512Y228347D02*
X403668Y230191D01*
G01X411762Y233908D02*
X413386Y232284D01*
G01X409569Y233908D02*
X411762D01*
G01X407500Y235977D02*
X409569Y233908D01*
G01X407500Y240363D02*
Y235977D01*
G01X400159Y228641D02*
X401727D01*
G01X398066Y230734D02*
X400159Y228641D01*
G01X396795Y230734D02*
X398066D01*
G01X389329Y238200D02*
X396795Y230734D01*
G01X410171Y196500D02*
X394900D01*
G01X392501Y186500D02*
X404371D01*
G01X404700Y189000D02*
X392830D01*
G01X396306Y238600D02*
X397452D01*
G01X392706Y242200D02*
X396306Y238600D01*
G01X415666Y238500D02*
X417323Y240157D01*
G01X412852Y238500D02*
X415666D01*
G01X411736Y239616D02*
X412852Y238500D01*
G01X411736Y244001D02*
Y239616D01*
G01X409255Y246482D02*
X411736Y244001D01*
G01X408806Y246482D02*
X409255D01*
G01X407899Y247389D02*
X408806Y246482D01*
G01X407899Y247838D02*
Y247389D01*
G01X405937Y249800D02*
X407899Y247838D01*
G01X431200Y298700D02*
Y299899D01*
G01X429900Y297400D02*
X431200Y298700D01*
G01X387235Y297400D02*
X429900D01*
G01X401381Y242545D02*
X403700Y240226D01*
G01X396995Y242545D02*
X401381D01*
G01X395340Y244200D02*
X396995Y242545D01*
G01X429899Y293500D02*
X387607D01*
G01X431302Y294903D02*
X429899Y293500D01*
G01X431302Y296102D02*
Y294903D01*
G01X432547Y297347D02*
X431302Y296102D01*
G01X433846Y297347D02*
X432547D01*
G01X435048Y298549D02*
X433846Y297347D01*
G01X435048Y299848D02*
Y298549D01*
G01X448818Y293581D02*
X449318Y293081D01*
G01X448818Y295276D02*
Y293581D01*
G01X405318Y242545D02*
X407500Y240363D01*
G01X404869Y242545D02*
X405318D01*
G01X403962Y243452D02*
X404869Y242545D01*
G01X403962Y243901D02*
Y243452D01*
G01X401381Y246482D02*
X403962Y243901D01*
G01X437008Y293823D02*
Y295276D01*
G01X435164Y291979D02*
X437008Y293823D01*
G01X435164Y291055D02*
Y291979D01*
G01X433500Y289391D02*
X435164Y291055D01*
G01X432630Y289391D02*
X433500D01*
G01X431031Y287792D02*
X432630Y289391D01*
G01X431031Y286831D02*
Y287792D01*
G01X429700Y285500D02*
X431031Y286831D01*
G01X387530Y285500D02*
X429700D01*
G01X389000Y273800D02*
X387000Y275800D01*
G01X429536Y273800D02*
X389000D01*
G01X431269Y275533D02*
X429536Y273800D01*
G01X431269Y275982D02*
Y275533D01*
G01X433081Y277794D02*
X431269Y275982D01*
G01X433529Y277794D02*
X433081D01*
G01X435139Y279404D02*
X433529Y277794D01*
G01X435139Y280263D02*
Y279404D01*
G01X440945Y286069D02*
X435139Y280263D01*
G01X440945Y287402D02*
Y286069D01*
G01X410999Y248675D02*
X405474Y254200D01*
G01X410999Y248226D02*
Y248675D01*
G01X413580Y245645D02*
X410999Y248226D01*
G01X414029Y245645D02*
X413580D01*
G01X415351Y244323D02*
X414029Y245645D01*
G01X415351Y243491D02*
Y244323D01*
G01X416684Y242158D02*
X415351Y243491D01*
G01X419259Y242158D02*
X416684D01*
G01X421259Y240158D02*
X419259Y242158D01*
G01X439221Y297000D02*
X440945Y295276D01*
G01X436099Y297000D02*
X439221D01*
G01X434900Y295801D02*
X436099Y297000D01*
G01X434900Y294700D02*
Y295801D01*
G01X433300Y293100D02*
X434900Y294700D01*
G01X432299Y293100D02*
X433300D01*
G01X431108Y291909D02*
X432299Y293100D01*
G01X431108Y290808D02*
Y291909D01*
G01X429900Y289600D02*
X431108Y290808D01*
G01X388351Y289600D02*
X429900D01*
G01X428501Y281700D02*
X388500D01*
G01X431969Y285168D02*
X428501Y281700D01*
G01X433468Y285168D02*
X431969D01*
G01X434998Y286698D02*
X433468Y285168D01*
G01X434998Y287969D02*
Y286698D01*
G01X436432Y289403D02*
X434998Y287969D01*
G01X437503Y289403D02*
X436432D01*
G01X438758Y290658D02*
X437503Y289403D01*
G01X438758Y291757D02*
Y290658D01*
G01X440100Y293099D02*
X438758Y291757D01*
G01X441499Y293099D02*
X440100D01*
G01X442700Y294300D02*
X441499Y293099D01*
G01X442700Y297227D02*
Y294300D01*
G01X440945Y298982D02*
X442700Y297227D01*
G01X440945Y299213D02*
Y298982D01*
G01X419384Y245971D02*
X421260Y244095D01*
G01X417191Y245971D02*
X419384D01*
G01X415773Y247389D02*
X417191Y245971D01*
G01X415773Y267523D02*
Y247389D01*
G01X413596Y269700D02*
X415773Y267523D01*
G01X429652Y277853D02*
X388725D01*
G01X431015Y279216D02*
X429652Y277853D01*
G01X431015Y279666D02*
Y279216D01*
G01X432849Y281500D02*
X431015Y279666D01*
G01X433999Y281500D02*
X432849D01*
G01X439195Y286696D02*
X433999Y281500D01*
G01X439195Y289095D02*
Y286696D01*
G01X440945Y290845D02*
X439195Y289095D01*
G01X440945Y291339D02*
Y290845D01*
G01X424336Y328578D02*
X389128D01*
G01X428314Y324600D02*
X424336Y328578D01*
G01X435260Y324600D02*
X428314D01*
G01X437864Y327204D02*
X435260Y324600D01*
G01X438976Y327204D02*
X437864D01*
G01X440417Y345000D02*
X444100D01*
G01X433644Y351773D02*
X440417Y345000D01*
G01X439161Y305303D02*
X440945Y307087D01*
G01X436657Y305303D02*
X439161D01*
G01X434932Y303578D02*
X436657Y305303D01*
G01X434932Y302432D02*
Y303578D01*
G01X433825Y301325D02*
X434932Y302432D01*
G01X432626Y301325D02*
X433825D01*
G01X431200Y299899D02*
X432626Y301325D01*
G01X438614Y352840D02*
X437681Y353773D01*
G01X438614Y352132D02*
Y352840D01*
G01X437795Y351313D02*
X438614Y352132D01*
G01X437795Y350605D02*
Y351313D01*
G01X438502Y349898D02*
X437795Y350605D01*
G01X439210Y349898D02*
X438502D01*
G01X440029Y350717D02*
X439210Y349898D01*
G01X440737Y350717D02*
X440029D01*
G01X443404Y348050D02*
X440737Y350717D01*
G01X443667Y348050D02*
X443404D01*
G01X446101Y345616D02*
X443667Y348050D01*
G01X446101Y336772D02*
Y345616D01*
G01X452950Y329923D02*
X446101Y336772D01*
G01X448819Y308513D02*
X451500Y311194D01*
G01X448819Y307088D02*
Y308513D01*
G01X436400Y301200D02*
X435048Y299848D01*
G01X438995Y301200D02*
X436400D01*
G01X440945Y303150D02*
X438995Y301200D01*
G01X446200Y326517D02*
Y327400D01*
G01X444283Y324600D02*
X446200Y326517D01*
G01X440316Y324600D02*
X444283D01*
G01X438316Y322600D02*
X440316Y324600D01*
G01X428514Y322600D02*
X438316D01*
G01X427053Y321139D02*
X428514Y322600D01*
G01X408270Y340700D02*
X407770Y341200D01*
G01X408270Y339900D02*
Y340700D01*
G01X408770Y339400D02*
X408270Y339900D01*
G01X409770Y339400D02*
X408770D01*
G01X410270Y339900D02*
X409770Y339400D01*
G01X410270Y340700D02*
Y339900D01*
G01X410770Y341200D02*
X410270Y340700D01*
G01X411770Y341200D02*
X410770D01*
G01X412270Y340700D02*
X411770Y341200D01*
G01X412270Y339900D02*
Y340700D01*
G01X412770Y339400D02*
X412270Y339900D01*
G01X413770Y339400D02*
X412770D01*
G01X414270Y339900D02*
X413770Y339400D01*
G01X414270Y340700D02*
Y339900D01*
G01X414770Y341200D02*
X414270Y340700D01*
G01X415770Y341200D02*
X414770D01*
G01X416270Y340700D02*
X415770Y341200D01*
G01X416270Y339900D02*
Y340700D01*
G01X416770Y339400D02*
X416270Y339900D01*
G01X417770Y339400D02*
X416770D01*
G01X418270Y339900D02*
X417770Y339400D01*
G01X418270Y340700D02*
Y339900D01*
G01X418770Y341200D02*
X418270Y340700D01*
G01X419770Y341200D02*
X418770D01*
G01X420270Y340700D02*
X419770Y341200D01*
G01X420270Y339900D02*
Y340700D01*
G01X420770Y339400D02*
X420270Y339900D01*
G01X421770Y339400D02*
X420770D01*
G01X422270Y339900D02*
X421770Y339400D01*
G01X422270Y340700D02*
Y339900D01*
G01X422770Y341200D02*
X422270Y340700D01*
G01X423770Y341200D02*
X422770D01*
G01X424270Y340700D02*
X423770Y341200D01*
G01X424270Y339200D02*
Y340700D01*
G01X424770Y338700D02*
X424270Y339200D01*
G01X425770Y338700D02*
X424770D01*
G01X426270Y339200D02*
X425770Y338700D01*
G01X426270Y340700D02*
Y339200D01*
G01X426770Y341200D02*
X426270Y340700D01*
G01X427770Y341200D02*
X426770D01*
G01X428270Y340700D02*
X427770Y341200D01*
G01X428270Y339900D02*
Y340700D01*
G01X432320Y335850D02*
X428270Y339900D01*
G01X445603Y335850D02*
X432320D01*
G01X451950Y329503D02*
X445603Y335850D01*
G01X448818Y311024D02*
X450500Y312706D01*
G01X454550Y352562D02*
X445131Y361981D01*
G01X452550Y351733D02*
X444302Y359981D01*
G01X436431Y337500D02*
X440300D01*
G01X430731Y343200D02*
X436431Y337500D01*
G01X425600Y316800D02*
X388900D01*
G01X427000Y318200D02*
X425600Y316800D01*
G01X427000Y319501D02*
Y318200D01*
G01X429099Y321600D02*
X427000Y319501D01*
G01X439709Y321600D02*
X429099D01*
G01X440944Y322835D02*
X439709Y321600D01*
G01X442100Y343000D02*
X444100Y341000D01*
G01X437183Y343000D02*
X442100D01*
G01X432850Y347333D02*
X437183Y343000D01*
G01X432850Y347917D02*
Y347333D01*
G01X430994Y349773D02*
X432850Y347917D01*
G01X425083Y349773D02*
X430994D01*
G01X424583Y349273D02*
X425083Y349773D01*
G01X424583Y347700D02*
Y349273D01*
G01X424083Y347200D02*
X424583Y347700D01*
G01X423083Y347200D02*
X424083D01*
G01X422583Y347700D02*
X423083Y347200D01*
G01X422583Y349273D02*
Y347700D01*
G01X422083Y349773D02*
X422583Y349273D01*
G01X421083Y349773D02*
X422083D01*
G01X420583Y349273D02*
X421083Y349773D01*
G01X420583Y347700D02*
Y349273D01*
G01X420083Y347200D02*
X420583Y347700D01*
G01X419083Y347200D02*
X420083D01*
G01X418583Y347700D02*
X419083Y347200D01*
G01X418583Y349273D02*
Y347700D01*
G01X418083Y349773D02*
X418583Y349273D01*
G01X410613Y349773D02*
X418083D01*
G01X410113Y349273D02*
X410613Y349773D01*
G01X410113Y347800D02*
Y349273D01*
G01X409613Y347300D02*
X410113Y347800D01*
G01X408613Y347300D02*
X409613D01*
G01X408113Y347800D02*
X408613Y347300D01*
G01X408113Y349273D02*
Y347800D01*
G01X407613Y349773D02*
X408113Y349273D01*
G01X403505Y349773D02*
X407613D01*
G01X403005Y349273D02*
X403505Y349773D01*
G01X403005Y347700D02*
Y349273D01*
G01X402505Y347200D02*
X403005Y347700D01*
G01X401505Y347200D02*
X402505D01*
G01X401005Y347700D02*
X401505Y347200D01*
G01X401005Y349273D02*
Y347700D01*
G01X400505Y349773D02*
X401005Y349273D01*
G01X399505Y349773D02*
X400505D01*
G01X399005Y349273D02*
X399505Y349773D01*
G01X399005Y347700D02*
Y349273D01*
G01X398505Y347200D02*
X399005Y347700D01*
G01X397505Y347200D02*
X398505D01*
G01X397005Y347700D02*
X397505Y347200D01*
G01X397005Y349273D02*
Y347700D01*
G01X396505Y349773D02*
X397005Y349273D01*
G01X395505Y349773D02*
X396505D01*
G01X395005Y349273D02*
X395505Y349773D01*
G01X395005Y347700D02*
Y349273D01*
G01X394505Y347200D02*
X395005Y347700D01*
G01X393505Y347200D02*
X394505D01*
G01X393005Y347700D02*
X393505Y347200D01*
G01X393005Y349273D02*
Y347700D01*
G01X392505Y349773D02*
X393005Y349273D01*
G01X391505Y349773D02*
X392505D01*
G01X391005Y349273D02*
X391505Y349773D01*
G01X391005Y347700D02*
Y349273D01*
G01X390505Y347200D02*
X391005Y347700D01*
G01X389505Y347200D02*
X390505D01*
G01X389005Y347700D02*
X389505Y347200D01*
G01X389005Y349273D02*
Y347700D01*
G01X388505Y349773D02*
X389005Y349273D01*
G01X387505Y349773D02*
X388505D01*
G01X387005Y349273D02*
X387505Y349773D01*
G01X387005Y347700D02*
Y349273D01*
G01X428646Y328513D02*
X425581Y331578D01*
G01X433345Y328513D02*
X428646D01*
G01X437682Y332850D02*
X433345Y328513D01*
G01X444358Y332850D02*
X437682D01*
G01X448950Y328258D02*
X444358Y332850D01*
G01X445098Y318898D02*
X448950Y322750D01*
G01X444882Y318898D02*
X445098D01*
G01X429495Y300994D02*
X386908D01*
G01X431341Y302840D02*
X429495Y300994D01*
G01X431341Y303941D02*
Y302840D01*
G01X432400Y305000D02*
X431341Y303941D01*
G01X433601Y305000D02*
X432400D01*
G01X434971Y306370D02*
X433601Y305000D01*
G01X434971Y307771D02*
Y306370D01*
G01X436200Y309000D02*
X434971Y307771D01*
G01X438921Y309000D02*
X436200D01*
G01X440945Y311024D02*
X438921Y309000D01*
G01X444035Y322835D02*
X444881D01*
G01X441800Y320600D02*
X444035Y322835D01*
G01X432396Y320600D02*
X441800D01*
G01X431300Y319504D02*
X432396Y320600D01*
G01X431300Y318599D02*
Y319504D01*
G01X429701Y317000D02*
X431300Y318599D01*
G01X428574Y317000D02*
X429701D01*
G01X427200Y315626D02*
X428574Y317000D01*
G01X427200Y314299D02*
Y315626D01*
G01X425677Y312776D02*
X427200Y314299D01*
G01X387691Y312776D02*
X425677D01*
G01X440800Y341000D02*
X444200Y337600D01*
G01X435900Y341000D02*
X440800D01*
G01X431700Y345200D02*
X435900Y341000D01*
G01X440234Y354049D02*
X438510Y355773D01*
G01X440940Y354049D02*
X440234D01*
G01X442291Y355401D02*
X440940Y354049D01*
G01X442997Y355401D02*
X442291D01*
G01X443706Y354692D02*
X442997Y355401D01*
G01X443706Y353986D02*
Y354692D01*
G01X442355Y352634D02*
X443706Y353986D01*
G01X442355Y351928D02*
Y352634D01*
G01X444233Y350050D02*
X442355Y351928D01*
G01X444496Y350050D02*
X444233D01*
G01X448300Y346246D02*
X444496Y350050D01*
G01X448300Y337500D02*
Y346246D01*
G01X429061Y329513D02*
X425996Y332578D01*
G01X432027Y329513D02*
X429061D01*
G01X436364Y333850D02*
X432027Y329513D01*
G01X444773Y333850D02*
X436364D01*
G01X449950Y328673D02*
X444773Y333850D01*
G01X447200Y319516D02*
X449950Y322266D01*
G01X447200Y318799D02*
Y319516D01*
G01X445301Y316900D02*
X447200Y318799D01*
G01X444400Y316900D02*
X445301D01*
G01X443100Y315600D02*
X444400Y316900D01*
G01X443100Y302739D02*
Y315600D01*
G01X444439Y301400D02*
X443100Y302739D01*
G01X453630Y301400D02*
X444439D01*
G01X429286Y331263D02*
X431102D01*
G01X426971Y333578D02*
X429286Y331263D01*
G01X417868Y333578D02*
X426971D01*
G01X416912Y334534D02*
X417868Y333578D01*
G01X388705Y334534D02*
X416912D01*
G01X441404Y327204D02*
X442913D01*
G01X437800Y323600D02*
X441404Y327204D01*
G01X427899Y323600D02*
X437800D01*
G01X426729Y324770D02*
X427899Y323600D01*
G01X388059Y324770D02*
X426729D01*
G01X428231Y327513D02*
X425166Y330578D01*
G01X433772Y327513D02*
X428231D01*
G01X438109Y331850D02*
X433772Y327513D01*
G01X443943Y331850D02*
X438109D01*
G01X447950Y327843D02*
X443943Y331850D01*
G01X447950Y323251D02*
Y327843D01*
G01X445799Y321100D02*
X447950Y323251D01*
G01X444599Y321100D02*
X445799D01*
G01X443200Y319701D02*
X444599Y321100D01*
G01X443200Y318960D02*
Y319701D01*
G01X441040Y316800D02*
X443200Y318960D01*
G01X436400Y316800D02*
X441040D01*
G01X434561Y314961D02*
X436400Y316800D01*
G01X433071Y314961D02*
X434561D01*
G01X447269Y317348D02*
X444882Y314961D01*
G01X449462Y317348D02*
X447269D01*
G01X445188Y334850D02*
X450950Y329088D01*
G01X419336Y334850D02*
X445188D01*
G01X416912Y337274D02*
X419336Y334850D01*
G01X404926Y337274D02*
X416912D01*
G01X403000Y339200D02*
X404926Y337274D01*
G01X456550Y353391D02*
X445960Y363981D01*
G01X429240Y305000D02*
X389279D01*
G01X431108Y306868D02*
X429240Y305000D01*
G01X431108Y308009D02*
Y306868D01*
G01X432304Y309205D02*
X431108Y308009D01*
G01X433445Y309205D02*
X432304D01*
G01X435163Y310923D02*
X433445Y309205D01*
G01X435163Y313116D02*
Y310923D01*
G01X437008Y314961D02*
X435163Y313116D01*
G01X438749Y330300D02*
X442800D01*
G01X434962Y326513D02*
X438749Y330300D01*
G01X427816Y326513D02*
X434962D01*
G01X424751Y329578D02*
X427816Y326513D01*
G01X387918Y329578D02*
X424751D01*
G01X430992Y310293D02*
X429999Y309300D01*
G01X430992Y315591D02*
Y310293D01*
G01X432201Y316800D02*
X430992Y315591D01*
G01X434910Y316800D02*
X432201D01*
G01X437008Y318898D02*
X434910Y316800D01*
G01X450300Y351154D02*
X443473Y357981D01*
G01X448818Y303151D02*
X451027Y305360D01*
G01X448725Y369981D02*
X462550Y356156D01*
G01X447067Y365981D02*
X458550Y354498D01*
G01X460550Y355327D02*
X447896Y367981D01*
G01X449452Y56284D02*
Y28980D01*
G01X456429Y33594D02*
X451969Y29134D01*
G01X456429Y56409D02*
Y33594D01*
G01X454429Y37106D02*
Y55580D01*
G01X451969Y34646D02*
X454429Y37106D01*
G01X536982Y66886D02*
X476568Y127300D01*
G01X477326Y132200D02*
X538640Y70886D01*
G01X478533Y136980D02*
X540627Y74886D01*
G01X539798Y72886D02*
X477731Y134953D01*
G01X476897Y129800D02*
X537811Y68886D01*
G01X542285Y78886D02*
X480191Y140980D01*
G01X541456Y76886D02*
X479362Y138980D01*
G01X543114Y80886D02*
X481000Y143000D01*
G01X485684Y167499D02*
X551263Y101920D01*
G01X547118Y91920D02*
X481780Y157258D01*
G01X546289Y89920D02*
X481866Y154343D01*
G01X550434Y99920D02*
X484855Y165499D01*
G01X544631Y85920D02*
X481531Y149020D01*
G01X543802Y83920D02*
X481871Y145851D01*
G01X552092Y103920D02*
X486513Y169499D01*
G01X483197Y161499D02*
X548776Y95920D01*
G01X549605Y97920D02*
X484026Y163499D01*
G01X481825Y151555D02*
X545460Y87920D01*
G01X482368Y159499D02*
X547947Y93920D01*
G01X467639Y291339D02*
X460630D01*
G01X469300Y293000D02*
X467639Y291339D01*
G01X473100Y293000D02*
X469300D01*
G01X474417Y294317D02*
X473100Y293000D01*
G01X474417Y299000D02*
Y294317D01*
G01X477017Y301600D02*
X474417Y299000D01*
G01X486415Y293503D02*
X484252Y291340D01*
G01X486415Y296023D02*
Y293503D01*
G01X487892Y297500D02*
X486415Y296023D01*
G01X490000Y297500D02*
X487892D01*
G01X491800Y299300D02*
X490000Y297500D01*
G01X493300Y299300D02*
X491800D01*
G01X494924Y300924D02*
X493300Y299300D01*
G01X454261Y291340D02*
X452755D01*
G01X456020Y293099D02*
X454261Y291340D01*
G01X457299Y293099D02*
X456020D01*
G01X458600Y294400D02*
X457299Y293099D01*
G01X458600Y295899D02*
Y294400D01*
G01X460201Y297500D02*
X458600Y295899D01*
G01X465800Y297500D02*
X460201D01*
G01X466400Y298100D02*
X465800Y297500D01*
G01X466400Y300400D02*
Y298100D01*
G01X452755Y296847D02*
Y295277D01*
G01X454707Y298799D02*
X452755Y296847D01*
G01X454707Y299618D02*
Y298799D01*
G01X456063Y300974D02*
X454707Y299618D01*
G01X482702Y289789D02*
X480316Y287403D01*
G01X482702Y296000D02*
Y289789D01*
G01X483602Y296900D02*
X482702Y296000D01*
G01X484400Y296900D02*
X483602D01*
G01X486100Y298600D02*
X484400Y296900D01*
G01X486100Y300300D02*
Y298600D01*
G01X489933Y295276D02*
X488189D01*
G01X492078Y297421D02*
X489933Y295276D01*
G01X500556Y297421D02*
X492078D01*
G01X502347Y299212D02*
X500556Y297421D01*
G01X502347Y299816D02*
Y299212D01*
G01X480161Y291339D02*
X480315D01*
G01X478000Y293500D02*
X480161Y291339D01*
G01X478000Y296200D02*
Y293500D01*
G01X479300Y297500D02*
X478000Y296200D01*
G01X481600Y297500D02*
X479300D01*
G01X482500Y298400D02*
X481600Y297500D01*
G01X482500Y300600D02*
Y298400D01*
G01X458800Y298660D02*
Y299952D01*
G01X457540Y297400D02*
X458800Y298660D01*
G01X455700Y297400D02*
X457540D01*
G01X454832Y296532D02*
X455700Y297400D01*
G01X454832Y294810D02*
Y296532D01*
G01X453103Y293081D02*
X454832Y294810D01*
G01X449318Y293081D02*
X453103D01*
G01X505487Y295082D02*
X514025Y303620D01*
G01X505487Y294633D02*
Y295082D01*
G01X504580Y293726D02*
X505487Y294633D01*
G01X504131Y293726D02*
X504580D01*
G01X502387Y291982D02*
X504131Y293726D01*
G01X502387Y291378D02*
Y291982D01*
G01X500565Y289556D02*
X502387Y291378D01*
G01X495400Y289556D02*
X500565D01*
G01X493900Y288056D02*
X495400Y289556D01*
G01X493900Y286800D02*
Y288056D01*
G01X492952Y285852D02*
X493900Y286800D01*
G01X473992Y285852D02*
X492952D01*
G01X472442Y287402D02*
X473992Y285852D01*
G01X486350Y289500D02*
X484252Y287402D01*
G01X492500Y289500D02*
X486350D01*
G01X494200Y291200D02*
X492500Y289500D01*
G01X494200Y292200D02*
Y291200D01*
G01X495475Y293475D02*
X494200Y292200D01*
G01X500547Y293475D02*
X495475D01*
G01X502178Y295106D02*
X500547Y293475D01*
G01X502178Y295710D02*
Y295106D01*
G01X503964Y297496D02*
X502178Y295710D01*
G01X504413Y297496D02*
X503964D01*
G01X509781Y302864D02*
X504413Y297496D01*
G01X476560Y298700D02*
X479160Y301300D01*
G01X476560Y294232D02*
Y298700D01*
G01X474828Y292500D02*
X476560Y294232D01*
G01X474828Y290928D02*
Y292500D01*
G01X473000Y289100D02*
X474828Y290928D01*
G01X466266Y289100D02*
X473000D01*
G01X464568Y287402D02*
X466266Y289100D01*
G01X454435Y289082D02*
X452755Y287402D01*
G01X457682Y289082D02*
X454435D01*
G01X458800Y290200D02*
X457682Y289082D01*
G01X458800Y292489D02*
Y290200D01*
G01X459700Y293389D02*
X458800Y292489D01*
G01X465389Y293389D02*
X459700D01*
G01X470300Y298300D02*
X465389Y293389D01*
G01X470300Y300300D02*
Y298300D01*
G01X477021Y301600D02*
X477017D01*
G01X478367Y302946D02*
X477021Y301600D01*
G01X478367Y307332D02*
Y302946D01*
G01X484446Y313411D02*
X478367Y307332D01*
G01X484895Y313411D02*
X484446D01*
G01X485802Y314318D02*
X484895Y313411D01*
G01X485802Y326578D02*
Y314318D01*
G01X495877Y336653D02*
X485802Y326578D01*
G01X495877Y351651D02*
Y336653D01*
G01X491350Y356178D02*
X495877Y351651D01*
G01X491350Y361450D02*
Y356178D01*
G01X491850Y361950D02*
X491350Y361450D01*
G01X500122Y300924D02*
X494924D01*
G01X502145Y302947D02*
X500122Y300924D01*
G01X502145Y307488D02*
Y302947D01*
G01X503294Y308637D02*
X502145Y307488D01*
G01X503743Y308637D02*
X503294D01*
G01X506324Y311218D02*
X503743Y308637D01*
G01X506324Y311667D02*
Y311218D01*
G01X507231Y312574D02*
X506324Y311667D01*
G01X507680Y312574D02*
X507231D01*
G01X509680Y314574D02*
X507680Y312574D01*
G01X509680Y328969D02*
Y314574D01*
G01X513345Y332634D02*
X509680Y328969D01*
G01X452950Y320749D02*
Y329923D01*
G01X452400Y320199D02*
X452950Y320749D01*
G01X452400Y317456D02*
Y320199D01*
G01X451500Y316556D02*
X452400Y317456D01*
G01X451500Y311194D02*
Y316556D01*
G01X467300Y301300D02*
X466400Y300400D01*
G01X469300Y301300D02*
X467300D01*
G01X470200Y302200D02*
X469300Y301300D01*
G01X470200Y304200D02*
Y302200D01*
G01X471100Y305100D02*
X470200Y304200D01*
G01X473200Y305100D02*
X471100D01*
G01X474357Y306257D02*
X473200Y305100D01*
G01X474357Y312059D02*
Y306257D01*
G01X475357Y313059D02*
X474357Y312059D01*
G01X478511Y313059D02*
X475357D01*
G01X480600Y315148D02*
X478511Y313059D01*
G01X480600Y320499D02*
Y315148D01*
G01X482200Y322099D02*
X480600Y320499D01*
G01X482200Y328523D02*
Y322099D01*
G01X491877Y338200D02*
X482200Y328523D01*
G01X491877Y349993D02*
Y338200D01*
G01X487350Y354520D02*
X491877Y349993D01*
G01X487350Y357217D02*
Y354520D01*
G01X483212Y361355D02*
X487350Y357217D01*
G01X483212Y367529D02*
Y361355D01*
G01X458800Y309194D02*
X456693Y307087D01*
G01X458800Y315324D02*
Y309194D01*
G01X460600Y317124D02*
X458800Y315324D01*
G01X462158Y317124D02*
X460600D01*
G01X463017Y317983D02*
X462158Y317124D01*
G01X463017Y320225D02*
Y317983D01*
G01X462300Y320942D02*
X463017Y320225D01*
G01X460162Y320942D02*
X462300D01*
G01X459662Y321442D02*
X460162Y320942D01*
G01X459662Y323392D02*
Y321442D01*
G01X460162Y323892D02*
X459662Y323392D01*
G01X464184Y323892D02*
X460162D01*
G01X467712Y327420D02*
X464184Y323892D01*
G01X467712Y327804D02*
Y327420D01*
G01X466073Y329443D02*
X467712Y327804D01*
G01X466073Y330151D02*
Y329443D01*
G01X466780Y330858D02*
X466073Y330151D01*
G01X467488Y330858D02*
X466780D01*
G01X469127Y329219D02*
X467488Y330858D01*
G01X469835Y329219D02*
X469127D01*
G01X470542Y329926D02*
X469835Y329219D01*
G01X470542Y330634D02*
Y329926D01*
G01X469405Y331771D02*
X470542Y330634D01*
G01X469405Y332832D02*
Y331771D01*
G01X473308Y336735D02*
X469405Y332832D01*
G01X473308Y342049D02*
Y336735D01*
G01X474350Y343091D02*
X473308Y342049D01*
G01X474350Y356047D02*
Y343091D01*
G01X473212Y357186D02*
X474350Y356047D01*
G01X473212Y362729D02*
Y357186D01*
G01X451950Y321350D02*
Y329503D01*
G01X451400Y320800D02*
X451950Y321350D01*
G01X451400Y317871D02*
Y320800D01*
G01X450500Y316971D02*
X451400Y317871D01*
G01X450500Y312706D02*
Y316971D01*
G01X457600Y300974D02*
X456063D01*
G01X458600Y301974D02*
X457600Y300974D01*
G01X458600Y304128D02*
Y301974D01*
G01X459600Y305128D02*
X458600Y304128D01*
G01X465128Y305128D02*
X459600D01*
G01X466425Y306425D02*
X465128Y305128D01*
G01X466425Y311728D02*
Y306425D01*
G01X467425Y312728D02*
X466425Y311728D01*
G01X469891Y312728D02*
X467425D01*
G01X470600Y313437D02*
X469891Y312728D01*
G01X470600Y315700D02*
Y313437D01*
G01X471649Y316749D02*
X470600Y315700D01*
G01X473200Y316749D02*
X471649D01*
G01X474200Y317749D02*
X473200Y316749D01*
G01X474200Y321342D02*
Y317749D01*
G01X476925Y324067D02*
X474200Y321342D01*
G01X476925Y329208D02*
Y324067D01*
G01X487877Y340160D02*
X476925Y329208D01*
G01X487877Y344039D02*
Y340160D01*
G01X487377Y344539D02*
X487877Y344039D01*
G01X486120Y344539D02*
X487377D01*
G01X485620Y345039D02*
X486120Y344539D01*
G01X485620Y346039D02*
Y345039D01*
G01X486120Y346539D02*
X485620Y346039D01*
G01X487377Y346539D02*
X486120D01*
G01X487877Y347039D02*
X487377Y346539D01*
G01X487877Y348335D02*
Y347039D01*
G01X483350Y352862D02*
X487877Y348335D01*
G01X483350Y355559D02*
Y352862D01*
G01X479212Y359697D02*
X483350Y355559D01*
G01X479212Y366469D02*
Y359697D01*
G01X454550Y336671D02*
Y352562D01*
G01X455450Y335771D02*
X454550Y336671D01*
G01X455450Y320150D02*
Y335771D01*
G01X454400Y319100D02*
X455450Y320150D01*
G01X454400Y316626D02*
Y319100D01*
G01X453800Y316026D02*
X454400Y316626D01*
G01X453800Y309839D02*
Y316026D01*
G01X454618Y309021D02*
X453800Y309839D01*
G01X454618Y305013D02*
Y309021D01*
G01X452755Y303150D02*
X454618Y305013D01*
G01X487050Y301250D02*
X486100Y300300D01*
G01X492419Y301250D02*
X487050D01*
G01X493800Y302631D02*
X492419Y301250D01*
G01X493800Y303235D02*
Y302631D01*
G01X496035Y305470D02*
X493800Y303235D01*
G01X496639Y305470D02*
X496035D01*
G01X498450Y307281D02*
X496639Y305470D01*
G01X498450Y307731D02*
Y307281D01*
G01X499356Y308637D02*
X498450Y307731D01*
G01X499805Y308637D02*
X499356D01*
G01X501753Y310585D02*
X499805Y308637D01*
G01X501753Y321203D02*
Y310585D01*
G01X504950Y324400D02*
X501753Y321203D01*
G01X504950Y330200D02*
Y324400D01*
G01X509250Y334500D02*
X504950Y330200D01*
G01X509250Y338613D02*
Y334500D01*
G01X515988Y345351D02*
X509250Y338613D01*
G01X509892Y352500D02*
X511796D01*
G01X504350Y358042D02*
X509892Y352500D01*
G01X504350Y363976D02*
Y358042D01*
G01X510138Y345159D02*
Y348500D01*
G01X505250Y340271D02*
X510138Y345159D01*
G01X505250Y336300D02*
Y340271D01*
G01X501150Y332200D02*
X505250Y336300D01*
G01X501150Y327000D02*
Y332200D01*
G01X497000Y322850D02*
X501150Y327000D01*
G01X497000Y322000D02*
Y322850D01*
G01X495448Y320448D02*
X497000Y322000D01*
G01X495420Y320448D02*
X495448D01*
G01X494513Y319541D02*
X495420Y320448D01*
G01X494513Y319513D02*
Y319541D01*
G01X493676Y318676D02*
X494513Y319513D01*
G01X493676Y310381D02*
Y318676D01*
G01X492397Y309102D02*
X493676Y310381D01*
G01X492397Y307358D02*
Y309102D01*
G01X492126Y307087D02*
X492397Y307358D01*
G01X503608Y301077D02*
X502347Y299816D01*
G01X504057Y301077D02*
X503608D01*
G01X506098Y303118D02*
X504057Y301077D01*
G01X506098Y307504D02*
Y303118D01*
G01X507926Y309332D02*
X506098Y307504D01*
G01X508375Y309332D02*
X507926D01*
G01X511186Y312143D02*
X508375Y309332D01*
G01X483000Y301100D02*
X482500Y300600D01*
G01X485000Y301100D02*
X483000D01*
G01X485802Y301902D02*
X485000Y301100D01*
G01X485802Y306893D02*
Y301902D01*
G01X488383Y309474D02*
X485802Y306893D01*
G01X488832Y309474D02*
X488383D01*
G01X489739Y310381D02*
X488832Y309474D01*
G01X489739Y318939D02*
Y310381D01*
G01X491800Y321000D02*
X489739Y318939D01*
G01X493000Y321000D02*
X491800D01*
G01X495500Y323500D02*
X493000Y321000D01*
G01X495500Y324700D02*
Y323500D01*
G01X499300Y328500D02*
X495500Y324700D01*
G01X499300Y332242D02*
Y328500D01*
G01X503250Y336192D02*
X499300Y332242D01*
G01X503250Y341100D02*
Y336192D01*
G01X506262Y344112D02*
X503250Y341100D01*
G01X506262Y348500D02*
Y344112D01*
G01X481212Y360526D02*
Y368536D01*
G01X485350Y356388D02*
X481212Y360526D01*
G01X485350Y353691D02*
Y356388D01*
G01X489877Y349164D02*
X485350Y353691D01*
G01X489877Y339277D02*
Y349164D01*
G01X478500Y327900D02*
X489877Y339277D01*
G01X478500Y317705D02*
Y327900D01*
G01X477765Y316970D02*
X478500Y317705D01*
G01X475828Y316970D02*
X477765D01*
G01X474400Y315542D02*
X475828Y316970D01*
G01X474400Y313637D02*
Y315542D01*
G01X473800Y313037D02*
X474400Y313637D01*
G01X471645Y313037D02*
X473800D01*
G01X470645Y312037D02*
X471645Y313037D01*
G01X470645Y306645D02*
Y312037D01*
G01X469300Y305300D02*
X470645Y306645D01*
G01X467400Y305300D02*
X469300D01*
G01X466500Y304400D02*
X467400Y305300D01*
G01X466500Y302500D02*
Y304400D01*
G01X465400Y301400D02*
X466500Y302500D01*
G01X461628Y301400D02*
X465400D01*
G01X461180Y300952D02*
X461628Y301400D01*
G01X459800Y300952D02*
X461180D01*
G01X458800Y299952D02*
X459800Y300952D01*
G01X452550Y337750D02*
Y351733D01*
G01X452300Y337500D02*
X452550Y337750D01*
G01X460630Y311911D02*
Y311024D01*
G01X466600Y317881D02*
X460630Y311911D01*
G01X466600Y320335D02*
Y317881D01*
G01X467100Y320835D02*
X466600Y320335D01*
G01X470005Y320835D02*
X467100D01*
G01X470505Y321335D02*
X470005Y320835D01*
G01X470505Y322335D02*
Y321335D01*
G01X470005Y322835D02*
X470505Y322335D01*
G01X467100Y322835D02*
X470005D01*
G01X466600Y323335D02*
X467100Y322835D01*
G01X466600Y324335D02*
Y323335D01*
G01X467100Y324835D02*
X466600Y324335D01*
G01X473096Y324835D02*
X467100D01*
G01X474196Y325935D02*
X473096Y324835D01*
G01X474196Y331093D02*
Y325935D01*
G01X473696Y331593D02*
X474196Y331093D01*
G01X471938Y331593D02*
X473696D01*
G01X471438Y332093D02*
X471938Y331593D01*
G01X471438Y333093D02*
Y332093D01*
G01X471938Y333593D02*
X471438Y333093D01*
G01X473696Y333593D02*
X471938D01*
G01X474196Y334093D02*
X473696Y333593D01*
G01X474196Y335396D02*
Y334093D01*
G01X476419Y337619D02*
X474196Y335396D01*
G01X479504Y337619D02*
X476419D01*
G01X480004Y338119D02*
X479504Y337619D01*
G01X480004Y339119D02*
Y338119D01*
G01X479504Y339619D02*
X480004Y339119D01*
G01X475918Y339619D02*
X479504D01*
G01X475418Y340119D02*
X475918Y339619D01*
G01X475418Y341119D02*
Y340119D01*
G01X475918Y341619D02*
X475418Y341119D01*
G01X480567Y341619D02*
X475918D01*
G01X481067Y342119D02*
X480567Y341619D01*
G01X481067Y343119D02*
Y342119D01*
G01X480567Y343619D02*
X481067Y343119D01*
G01X476903Y343619D02*
X480567D01*
G01X476403Y344119D02*
X476903Y343619D01*
G01X476403Y345119D02*
Y344119D01*
G01X476903Y345619D02*
X476403Y345119D01*
G01X478954Y345619D02*
X476903D01*
G01X479454Y346119D02*
X478954Y345619D01*
G01X479454Y349222D02*
Y346119D01*
G01X478954Y349722D02*
X479454Y349222D01*
G01X476861Y349722D02*
X478954D01*
G01X476361Y350222D02*
X476861Y349722D01*
G01X476361Y351222D02*
Y350222D01*
G01X476861Y351722D02*
X476361Y351222D01*
G01X478802Y351722D02*
X476861D01*
G01X479302Y352222D02*
X478802Y351722D01*
G01X479302Y353222D02*
Y352222D01*
G01X478802Y353722D02*
X479302Y353222D01*
G01X477056Y353722D02*
X478802D01*
G01X476556Y354222D02*
X477056Y353722D01*
G01X476556Y356693D02*
Y354222D01*
G01X476350Y356899D02*
X476556Y356693D01*
G01X475212Y358039D02*
X476350Y356899D01*
G01X475212Y363659D02*
Y358039D01*
G01X448950Y322750D02*
Y328258D01*
G01X490576Y305537D02*
X488189Y303150D01*
G01X492769Y305537D02*
X490576D01*
G01X494513Y307281D02*
X492769Y305537D01*
G01X494513Y307730D02*
Y307281D01*
G01X496257Y309474D02*
X494513Y307730D01*
G01X496706Y309474D02*
X496257D01*
G01X497613Y310381D02*
X496706Y309474D01*
G01X497613Y320113D02*
Y310381D01*
G01X502950Y325450D02*
X497613Y320113D01*
G01X502950Y331250D02*
Y325450D01*
G01X507250Y335550D02*
X502950Y331250D01*
G01X507250Y339442D02*
Y335550D01*
G01X512138Y344330D02*
X507250Y339442D01*
G01X510967Y350500D02*
X512138Y349329D01*
G01X509063Y350500D02*
X510967D01*
G01X502350Y357213D02*
X509063Y350500D01*
G01X502350Y364805D02*
Y357213D01*
G01X464300Y338143D02*
Y337500D01*
G01X462550Y339893D02*
X464300Y338143D01*
G01X462550Y356156D02*
Y339893D01*
G01X471134Y355364D02*
Y361978D01*
G01X472350Y354144D02*
X471134Y355364D01*
G01X472350Y343920D02*
Y354144D01*
G01X471308Y342878D02*
X472350Y343920D01*
G01X471308Y337679D02*
Y342878D01*
G01X464433Y330804D02*
X471308Y337679D01*
G01X464433Y326633D02*
Y330804D01*
G01X463300Y325500D02*
X464433Y326633D01*
G01X459056Y325500D02*
X463300D01*
G01X458556Y325000D02*
X459056Y325500D01*
G01X458556Y317271D02*
Y325000D01*
G01X458056Y316771D02*
X458556Y317271D01*
G01X456054Y316771D02*
X458056D01*
G01X454900Y315617D02*
X456054Y316771D01*
G01X454900Y312817D02*
Y315617D01*
G01X456693Y311024D02*
X454900Y312817D01*
G01X509781Y307700D02*
Y302864D01*
G01X512726Y310645D02*
X509781Y307700D01*
G01X462700Y308955D02*
X464567Y307088D01*
G01X462700Y311800D02*
Y308955D01*
G01X468002Y317102D02*
X462700Y311800D01*
G01X469800Y317102D02*
X468002D01*
G01X470714Y318016D02*
X469800Y317102D01*
G01X470714Y319589D02*
Y318016D01*
G01X475754Y324629D02*
X470714Y319589D01*
G01X475754Y329766D02*
Y324629D01*
G01X477900Y331912D02*
X475754Y329766D01*
G01X477900Y335500D02*
Y331912D01*
G01X478900Y336500D02*
X477900Y335500D01*
G01X481298Y336500D02*
X478900D01*
G01X483427Y338629D02*
X481298Y336500D01*
G01X483427Y349956D02*
Y338629D01*
G01X481350Y352033D02*
X483427Y349956D01*
G01X481350Y354730D02*
Y352033D01*
G01X477212Y358868D02*
X481350Y354730D01*
G01X477212Y364488D02*
Y358868D01*
G01X469053Y358164D02*
X464022Y363195D01*
G01X469053Y356188D02*
Y358164D01*
G01X468412Y355547D02*
X469053Y356188D01*
G01X467427Y355547D02*
X468412D01*
G01X466927Y355047D02*
X467427Y355547D01*
G01X466927Y354047D02*
Y355047D01*
G01X467427Y353547D02*
X466927Y354047D01*
G01X469572Y353547D02*
X467427D01*
G01X470072Y353047D02*
X469572Y353547D01*
G01X470072Y352047D02*
Y353047D01*
G01X469572Y351547D02*
X470072Y352047D01*
G01X467969Y351547D02*
X469572D01*
G01X467469Y351047D02*
X467969Y351547D01*
G01X467469Y350047D02*
Y351047D01*
G01X467969Y349547D02*
X467469Y350047D01*
G01X469612Y349547D02*
X467969D01*
G01X470350Y348809D02*
X469612Y349547D01*
G01X470350Y345314D02*
Y348809D01*
G01X469420Y344384D02*
X470350Y345314D01*
G01X467123Y344384D02*
X469420D01*
G01X466623Y343884D02*
X467123Y344384D01*
G01X466623Y341658D02*
Y343884D01*
G01X467123Y341158D02*
X466623Y341658D01*
G01X468585Y341158D02*
X467123D01*
G01X469085Y340658D02*
X468585Y341158D01*
G01X469085Y338285D02*
Y340658D01*
G01X468300Y337500D02*
X469085Y338285D01*
G01X449950Y322266D02*
Y328673D01*
G01X454949Y302719D02*
X453630Y301400D01*
G01X454949Y303686D02*
Y302719D01*
G01X456346Y305083D02*
X454949Y303686D01*
G01X457443Y305083D02*
X456346D01*
G01X459447Y307087D02*
X457443Y305083D01*
G01X460630Y307087D02*
X459447D01*
G01X502138Y343638D02*
Y348500D01*
G01X500901Y342401D02*
X502138Y343638D01*
G01X500901Y336672D02*
Y342401D01*
G01X497000Y332771D02*
X500901Y336672D01*
G01X497000Y328900D02*
Y332771D01*
G01X492800Y324700D02*
X497000Y328900D01*
G01X491250Y324700D02*
X492800D01*
G01X490200Y323650D02*
X491250Y324700D01*
G01X490200Y321650D02*
Y323650D01*
G01X487500Y318950D02*
X490200Y321650D01*
G01X487500Y313500D02*
Y318950D01*
G01X485802Y311802D02*
X487500Y313500D01*
G01X485802Y310381D02*
Y311802D01*
G01X484895Y309474D02*
X485802Y310381D01*
G01X484446Y309474D02*
X484895D01*
G01X482336Y307364D02*
X484446Y309474D01*
G01X482336Y302736D02*
Y307364D01*
G01X480900Y301300D02*
X482336Y302736D01*
G01X479160Y301300D02*
X480900D01*
G01X471200Y301200D02*
X470300Y300300D01*
G01X473300Y301200D02*
X471200D01*
G01X474799Y302699D02*
X473300Y301200D01*
G01X474799Y304252D02*
Y302699D01*
G01X476347Y305800D02*
X474799Y304252D01*
G01X476347Y308248D02*
Y305800D01*
G01X482400Y314301D02*
X476347Y308248D01*
G01X482400Y319800D02*
Y314301D01*
G01X483900Y321300D02*
X482400Y319800D01*
G01X483900Y327394D02*
Y321300D01*
G01X493877Y337371D02*
X483900Y327394D01*
G01X493877Y350822D02*
Y337371D01*
G01X489350Y355349D02*
X493877Y350822D01*
G01X489350Y361715D02*
Y355349D01*
G01X487400Y363665D02*
X489350Y361715D01*
G01X460300Y327400D02*
Y333500D01*
G01X459800Y326900D02*
X460300Y327400D01*
G01X456950Y326900D02*
X459800D01*
G01X456450Y327400D02*
X456950Y326900D01*
G01X456450Y334600D02*
Y327400D01*
G01X458550Y336700D02*
X456450Y334600D01*
G01X458550Y354498D02*
Y336700D01*
G01X496901Y360027D02*
Y364846D01*
G01X496850Y359976D02*
X496901Y360027D01*
G01X496850Y354450D02*
Y359976D01*
G01X500000Y351300D02*
X496850Y354450D01*
G01X500000Y346300D02*
Y351300D01*
G01X498900Y345200D02*
X500000Y346300D01*
G01X498900Y337500D02*
Y345200D01*
G01X496000Y334600D02*
X498900Y337500D01*
G01X496000Y332840D02*
Y334600D01*
G01X488189Y325029D02*
X496000Y332840D01*
G01X488189Y322835D02*
Y325029D01*
G01X462599Y331121D02*
Y327204D01*
G01X463564Y332086D02*
X462599Y331121D01*
G01X463564Y332794D02*
Y332086D01*
G01X461572Y334786D02*
X463564Y332794D01*
G01X461572Y335494D02*
Y334786D01*
G01X462279Y336201D02*
X461572Y335494D01*
G01X462987Y336201D02*
X462279D01*
G01X464979Y334209D02*
X462987Y336201D01*
G01X465687Y334209D02*
X464979D01*
G01X466350Y334872D02*
X465687Y334209D01*
G01X466350Y338922D02*
Y334872D01*
G01X464550Y340722D02*
X466350Y338922D01*
G01X464550Y344776D02*
Y340722D01*
G01X466350Y346576D02*
X464550Y344776D01*
G01X466350Y348177D02*
Y346576D01*
G01X464576Y349951D02*
X466350Y348177D01*
G01X464576Y359451D02*
Y349951D01*
G01X462832Y361195D02*
X464576Y359451D01*
G01X460340Y361195D02*
X462832D01*
G01X449554Y371981D02*
X460340Y361195D01*
G01X450400Y318286D02*
X449462Y317348D01*
G01X450400Y321301D02*
Y318286D01*
G01X450950Y321851D02*
X450400Y321301D01*
G01X450950Y329088D02*
Y321851D01*
G01X456550Y337500D02*
Y353391D01*
G01X505500Y312587D02*
X503937Y311024D01*
G01X505500Y322000D02*
Y312587D01*
G01X507100Y323600D02*
X505500Y322000D01*
G01X507100Y329250D02*
Y323600D01*
G01X511345Y333495D02*
X507100Y329250D01*
G01X460550Y337812D02*
Y355327D01*
G01X460800Y337562D02*
X460550Y337812D01*
G01X450300Y336671D02*
Y351154D01*
G01X451472Y335499D02*
X450300Y336671D01*
G01X452401Y335499D02*
X451472D01*
G01X454450Y333450D02*
X452401Y335499D01*
G01X454450Y320650D02*
Y333450D01*
G01X453400Y319600D02*
X454450Y320650D01*
G01X453400Y317041D02*
Y319600D01*
G01X452800Y316441D02*
X453400Y317041D01*
G01X452800Y309676D02*
Y316441D01*
G01X451027Y307903D02*
X452800Y309676D01*
G01X451027Y305360D02*
Y307903D01*
G01X491850Y368850D02*
Y361950D01*
G01X489500Y371200D02*
X491850Y368850D01*
G01X472557Y404684D02*
X602116D01*
G01X457599Y419642D02*
X472557Y404684D01*
G01X485101Y369418D02*
X483212Y367529D01*
G01X485101Y375387D02*
Y369418D01*
G01X474669Y385819D02*
X485101Y375387D01*
G01X473963Y385819D02*
X474669D01*
G01X473253Y385111D02*
X473963Y385819D01*
G01X473253Y384405D02*
Y385111D01*
G01X482829Y374829D02*
X473253Y384405D01*
G01X482829Y374123D02*
Y374829D01*
G01X482120Y373415D02*
X482829Y374123D01*
G01X481413Y373415D02*
X482120D01*
G01X468847Y385981D02*
X481413Y373415D01*
G01X466814Y369127D02*
X473212Y362729D01*
G01X466814Y369661D02*
Y369127D01*
G01X468018Y370865D02*
X466814Y369661D01*
G01X468018Y371573D02*
Y370865D01*
G01X467311Y372280D02*
X468018Y371573D01*
G01X466603Y372280D02*
X467311D01*
G01X465399Y371076D02*
X466603Y372280D01*
G01X464865Y371076D02*
X465399D01*
G01X463984Y371957D02*
X464865Y371076D01*
G01X463984Y372491D02*
Y371957D01*
G01X465188Y373695D02*
X463984Y372491D01*
G01X465188Y374403D02*
Y373695D01*
G01X464481Y375110D02*
X465188Y374403D01*
G01X463773Y375110D02*
X464481D01*
G01X462569Y373906D02*
X463773Y375110D01*
G01X462035Y373906D02*
X462569D01*
G01X461154Y374787D02*
X462035Y373906D01*
G01X461154Y375321D02*
Y374787D01*
G01X462358Y376525D02*
X461154Y375321D01*
G01X462358Y377233D02*
Y376525D01*
G01X461651Y377940D02*
X462358Y377233D01*
G01X460943Y377940D02*
X461651D01*
G01X459739Y376736D02*
X460943Y377940D01*
G01X459205Y376736D02*
X459739D01*
G01X457960Y377981D02*
X459205Y376736D01*
G01X475831Y369850D02*
X479212Y366469D01*
G01X473233Y369850D02*
X475831D01*
G01X472050Y371033D02*
X473233Y369850D01*
G01X472050Y373700D02*
Y371033D01*
G01X463769Y381981D02*
X472050Y373700D01*
G01X505583Y365209D02*
X504350Y363976D01*
G01X508600Y365209D02*
X505583D01*
G01X510700Y367309D02*
X508600Y365209D01*
G01X467356Y383481D02*
X466856Y383981D01*
G01X467356Y382981D02*
Y383481D01*
G01X466867Y382491D02*
X467356Y382981D01*
G01X466867Y381783D02*
Y382491D01*
G01X467574Y381076D02*
X466867Y381783D01*
G01X468282Y381076D02*
X467574D01*
G01X469226Y382020D02*
X468282Y381076D01*
G01X469934Y382020D02*
X469226D01*
G01X470641Y381313D02*
X469934Y382020D01*
G01X470641Y380605D02*
Y381313D01*
G01X469697Y379661D02*
X470641Y380605D01*
G01X469697Y378953D02*
Y379661D01*
G01X470404Y378246D02*
X469697Y378953D01*
G01X471112Y378246D02*
X470404D01*
G01X472056Y379190D02*
X471112Y378246D01*
G01X472764Y379190D02*
X472056D01*
G01X473471Y378483D02*
X472764Y379190D01*
G01X473471Y377775D02*
Y378483D01*
G01X472527Y376831D02*
X473471Y377775D01*
G01X472527Y376123D02*
Y376831D01*
G01X473234Y375416D02*
X472527Y376123D01*
G01X473942Y375416D02*
X473234D01*
G01X474886Y376360D02*
X473942Y375416D01*
G01X475594Y376360D02*
X474886D01*
G01X476301Y375653D02*
X475594Y376360D01*
G01X476301Y374945D02*
Y375653D01*
G01X475357Y374001D02*
X476301Y374945D01*
G01X475357Y373293D02*
Y374001D01*
G01X476064Y372586D02*
X475357Y373293D01*
G01X476772Y372586D02*
X476064D01*
G01X477716Y373530D02*
X476772Y372586D01*
G01X478424Y373530D02*
X477716D01*
G01X479131Y372823D02*
X478424Y373530D01*
G01X479131Y372115D02*
Y372823D01*
G01X478187Y371171D02*
X479131Y372115D01*
G01X478187Y370463D02*
Y371171D01*
G01X478894Y369756D02*
X478187Y370463D01*
G01X479602Y369756D02*
X478894D01*
G01X481213Y371367D02*
X479602Y369756D01*
G01X481921Y371367D02*
X481213D01*
G01X482628Y370660D02*
X481921Y371367D01*
G01X482628Y369952D02*
Y370660D01*
G01X481212Y368536D02*
X482628Y369952D01*
G01X470050Y368821D02*
X475212Y363659D01*
G01X470050Y372871D02*
Y368821D01*
G01X462940Y379981D02*
X470050Y372871D01*
G01X504854Y367309D02*
X502350Y364805D01*
G01X506700Y367309D02*
X504854D01*
G01X457419Y375260D02*
X456698Y375981D01*
G01X457419Y374638D02*
Y375260D01*
G01X455739Y372958D02*
X457419Y374638D01*
G01X455739Y371989D02*
Y372958D01*
G01X456446Y371282D02*
X455739Y371989D01*
G01X457154Y371282D02*
X456446D01*
G01X459181Y373309D02*
X457154Y371282D01*
G01X459803Y373309D02*
X459181D01*
G01X460596Y372516D02*
X459803Y373309D01*
G01X460596Y371894D02*
Y372516D01*
G01X458482Y369780D02*
X460596Y371894D01*
G01X458482Y369074D02*
Y369780D01*
G01X459190Y368364D02*
X458482Y369074D01*
G01X459896Y368364D02*
X459190D01*
G01X462011Y370479D02*
X459896Y368364D01*
G01X462633Y370479D02*
X462011D01*
G01X463426Y369686D02*
X462633Y370479D01*
G01X463426Y369064D02*
Y369686D01*
G01X461253Y366891D02*
X463426Y369064D01*
G01X461253Y366183D02*
Y366891D01*
G01X461960Y365476D02*
X461253Y366183D01*
G01X462668Y365476D02*
X461960D01*
G01X464841Y367649D02*
X462668Y365476D01*
G01X465463Y367649D02*
X464841D01*
G01X466256Y366856D02*
X465463Y367649D01*
G01X466256Y366234D02*
Y366856D01*
G01X465477Y365455D02*
X466256Y366234D01*
G01X465477Y364747D02*
Y365455D01*
G01X466184Y364040D02*
X465477Y364747D01*
G01X466892Y364040D02*
X466184D01*
G01X467671Y364819D02*
X466892Y364040D01*
G01X468293Y364819D02*
X467671D01*
G01X471134Y361978D02*
X468293Y364819D01*
G01X474200Y367500D02*
X477212Y364488D01*
G01X451006Y373358D02*
X450383Y373981D01*
G01X451714Y373358D02*
X451006D01*
G01X452320Y373964D02*
X451714Y373358D01*
G01X453028Y373964D02*
X452320D01*
G01X453735Y373257D02*
X453028Y373964D01*
G01X453735Y372549D02*
Y373257D01*
G01X453129Y371943D02*
X453735Y372549D01*
G01X453129Y371235D02*
Y371943D01*
G01X461169Y363195D02*
X453129Y371235D01*
G01X464022Y363195D02*
X461169D01*
G01X487400Y375917D02*
Y363665D01*
G01X475336Y387981D02*
X487400Y375917D01*
G01X497300Y377935D02*
X496300Y378935D01*
G01X497300Y365245D02*
Y377935D01*
G01X496901Y364846D02*
X497300Y365245D01*
G01X575556Y66886D02*
X536982D01*
G01X551263Y101920D02*
X599198D01*
G01X538640Y70886D02*
X580329D01*
G01X540627Y74886D02*
X583127D01*
G01X595053Y91920D02*
X547118D01*
G01X594224Y89920D02*
X546289D01*
G01X598369Y99920D02*
X550434D01*
G01X590671Y85920D02*
X544631D01*
G01X582298Y72886D02*
X539798D01*
G01X588995Y83920D02*
X543802D01*
G01X537811Y68886D02*
X579500D01*
G01X600027Y103920D02*
X552092D01*
G01X548776Y95920D02*
X596711D01*
G01X597540Y97920D02*
X549605D01*
G01X586552Y78886D02*
X542285D01*
G01X545460Y87920D02*
X592220D01*
G01X547947Y93920D02*
X595882D01*
G01X584259Y76886D02*
X541456D01*
G01X588227Y80886D02*
X543114D01*
G01X513345Y336637D02*
Y332634D01*
G01X522990Y346282D02*
X513345Y336637D01*
G01X538182Y346282D02*
X522990D01*
G01X540200Y348300D02*
X538182Y346282D01*
G01X515988Y349267D02*
Y345351D01*
G01X512905Y352350D02*
X515988Y349267D01*
G01X511946Y352350D02*
X512905D01*
G01X511796Y352500D02*
X511946Y352350D01*
G01X511186Y327646D02*
Y312143D01*
G01X514778Y331238D02*
X511186Y327646D01*
G01X514778Y335241D02*
Y331238D01*
G01X523819Y344282D02*
X514778Y335241D01*
G01X542082Y344282D02*
X523819D01*
G01X546100Y348300D02*
X542082Y344282D01*
G01X553802Y336302D02*
X556800Y339300D01*
G01X521665Y336302D02*
X553802D01*
G01X517750Y332387D02*
X521665Y336302D01*
G01X517750Y328715D02*
Y332387D01*
G01X514025Y324990D02*
X517750Y328715D01*
G01X514025Y303620D02*
Y324990D01*
G01X512138Y349329D02*
Y344330D01*
G01X512726Y326357D02*
Y310645D01*
G01X516345Y329976D02*
X512726Y326357D01*
G01X516345Y333979D02*
Y329976D01*
G01X522616Y340250D02*
X516345Y333979D01*
G01X548595Y340250D02*
X522616D01*
G01X550100Y341755D02*
X548595Y340250D01*
G01X550100Y348300D02*
Y341755D01*
G01X511345Y337466D02*
Y333495D01*
G01X522179Y348300D02*
X511345Y337466D01*
G01X536200Y348300D02*
X522179D01*
G01X589379Y32687D02*
Y53063D01*
G01X586614Y29922D02*
X589379Y32687D01*
G01X628026Y23189D02*
X635432D01*
G01X580329Y70886D02*
X628026Y23189D01*
G01X583127Y74886D02*
X626786Y31227D01*
G01X625807Y29377D02*
X582298Y72886D01*
G01X628260Y29377D02*
X625807D01*
G01X630492Y31609D02*
X628260Y29377D01*
G01X632416Y31609D02*
X630492D01*
G01X627197Y21189D02*
X636804D01*
G01X579500Y68886D02*
X627197Y21189D01*
G01X629423Y36015D02*
X586552Y78886D01*
G01X648449Y36015D02*
X629423D01*
G01X633111Y38015D02*
X627603Y43523D01*
G01X649278Y38015D02*
X633111D01*
G01X627130Y34015D02*
X584259Y76886D01*
G01X647620Y34015D02*
X627130D01*
G01X623613Y45500D02*
X588227Y80886D01*
G01X655668Y45500D02*
X623613D01*
G01X589379Y53063D02*
X575556Y66886D01*
G01X618829Y82289D02*
X711099D01*
G01X599198Y101920D02*
X618829Y82289D01*
G01X617473Y69500D02*
X595053Y91920D01*
G01X633500Y69500D02*
X617473D01*
G01X647850Y55150D02*
X633500Y69500D01*
G01X619644Y64500D02*
X594224Y89920D01*
G01X627500Y64500D02*
X619644D01*
G01X618000Y80289D02*
X598369Y99920D01*
G01X721271Y80289D02*
X618000D01*
G01X618091Y58500D02*
X590671Y85920D01*
G01X640800Y58500D02*
X618091D01*
G01X616415Y56500D02*
X588995Y83920D01*
G01X639971Y56500D02*
X616415D01*
G01X619658Y84289D02*
X600027Y103920D01*
G01X710270Y84289D02*
X619658D01*
G01X616342Y76289D02*
X722929D01*
G01X596711Y95920D02*
X616342Y76289D01*
G01X617171Y78289D02*
X597540Y97920D01*
G01X722100Y78289D02*
X617171D01*
G01X618640Y61500D02*
X629500D01*
G01X592220Y87920D02*
X618640Y61500D01*
G01X618302Y71500D02*
X638312D01*
G01X595882Y93920D02*
X618302Y71500D01*
G01X622100Y384700D02*
X644300D01*
G01X602116Y404684D02*
X622100Y384700D01*
G01X676717Y36160D02*
X702386Y61829D01*
G01X653962Y36160D02*
X676717D01*
G01X650107Y40015D02*
X653962Y36160D01*
G01X641098Y40015D02*
X650107D01*
G01X640144Y40969D02*
X641098Y40015D01*
G01X635432Y23189D02*
X643816Y31573D01*
G01X664301Y49998D02*
X659149Y55150D01*
G01X675425Y40800D02*
X667900D01*
G01X700835Y66210D02*
X675425Y40800D01*
G01X649700Y49600D02*
X640800Y58500D01*
G01X657887Y49600D02*
X649700D01*
G01X661468Y46019D02*
X657887Y49600D01*
G01X671519Y46019D02*
X661468D01*
G01X696395Y70895D02*
X671519Y46019D01*
G01X648871Y47600D02*
X639971Y56500D01*
G01X657058Y47600D02*
X648871D01*
G01X660639Y44019D02*
X657058Y47600D01*
G01X674519Y44019D02*
X660639D01*
G01X699395Y68895D02*
X674519Y44019D01*
G01X636804Y21189D02*
X647216Y31601D01*
G01X652304Y32160D02*
X648449Y36015D01*
G01X678375Y32160D02*
X652304D01*
G01X703615Y57400D02*
X678375Y32160D01*
G01X653133Y34160D02*
X649278Y38015D01*
G01X677546Y34160D02*
X653133D01*
G01X702786Y59400D02*
X677546Y34160D01*
G01X651475Y30160D02*
X647620Y34015D01*
G01X679585Y30160D02*
X651475D01*
G01X704825Y55400D02*
X679585Y30160D01*
G01X663008Y38160D02*
X655668Y45500D01*
G01X675614Y38160D02*
X663008D01*
G01X701283Y63829D02*
X675614Y38160D01*
G01X659149Y55150D02*
X647850D01*
G01X725342Y70895D02*
X696395D01*
G01X638312Y71500D02*
X641003Y68809D01*
G01X693110Y249049D02*
Y226478D01*
G01X690558Y205864D02*
X699980Y196442D01*
G01X690558Y223926D02*
Y205864D01*
G01X693110Y226478D02*
X690558Y223926D01*
G01X679527Y205373D02*
Y198424D01*
G01X676900Y208000D02*
X679527Y205373D01*
G01X676900Y215462D02*
Y208000D01*
G01X684962Y223524D02*
X676900Y215462D01*
G01X684962Y247518D02*
Y223524D01*
G01X701046Y249800D02*
X695600Y244354D01*
G01X695375Y260875D02*
X746828Y312328D01*
G01X704708Y260647D02*
X693110Y249049D01*
G01X749200Y311756D02*
X684962Y247518D01*
G01X658800Y409959D02*
X675101Y426260D01*
G01X658800Y401999D02*
Y409959D01*
G01X658601Y401800D02*
X658800Y401999D01*
G01X658700Y401701D02*
X658601Y401800D01*
G01X658700Y399100D02*
Y401701D01*
G01X644300Y384700D02*
X658700Y399100D01*
G01X676936Y421916D02*
X673900Y418880D01*
G01X698738Y421916D02*
X676936D01*
G01X695309Y428719D02*
X709632D01*
G01X692850Y426260D02*
X695309Y428719D01*
G01X675101Y426260D02*
X692850D01*
G01X744094Y25360D02*
Y24410D01*
G01X739552Y29902D02*
X744094Y25360D01*
G01X739552Y53787D02*
Y29902D01*
G01X747647Y37468D02*
Y56231D01*
G01X750469Y34646D02*
X747647Y37468D01*
G01X751181Y34646D02*
X750469D01*
G01X758267Y24410D02*
X767560Y33703D01*
G01X754663Y32616D02*
Y55393D01*
G01X751181Y29134D02*
X754663Y32616D01*
G01X758267Y29922D02*
X765560Y37215D01*
G01X713253Y32417D02*
Y54569D01*
G01X715748Y29922D02*
X713253Y32417D01*
G01X726695Y27942D02*
Y52471D01*
G01X729921Y24716D02*
X726695Y27942D01*
G01X729921Y24410D02*
Y24716D01*
G01X711253Y28905D02*
Y53740D01*
G01X715748Y24410D02*
X711253Y28905D01*
G01X741552Y32464D02*
Y54616D01*
G01X744094Y29922D02*
X741552Y32464D01*
G01X731510Y61829D02*
X739552Y53787D01*
G01X702386Y61829D02*
X731510D01*
G01X754462Y95313D02*
X767533D01*
G01X752497Y93348D02*
X754462Y95313D01*
G01X739654Y93348D02*
X752497D01*
G01X738507Y94495D02*
X739654Y93348D01*
G01X719536Y94495D02*
X738507D01*
G01X714962Y89921D02*
X719536Y94495D01*
G01X714962Y86152D02*
Y89921D01*
G01X711099Y82289D02*
X714962Y86152D01*
G01X737668Y66210D02*
X700835D01*
G01X747647Y56231D02*
X737668Y66210D01*
G01X726227Y85245D02*
X721271Y80289D01*
G01X748439Y85245D02*
X726227D01*
G01X767560Y66124D02*
X748439Y85245D01*
G01X731114Y76667D02*
X725342Y70895D01*
G01X747919Y76667D02*
X731114D01*
G01X755291Y93313D02*
X768362D01*
G01X753326Y91348D02*
X755291Y93313D01*
G01X738825Y91348D02*
X753326D01*
G01X737746Y92427D02*
X738825Y91348D01*
G01X720744Y92427D02*
X737746D01*
G01X726243Y68895D02*
X699395D01*
G01X731984Y74636D02*
X726243Y68895D01*
G01X750773Y74636D02*
X731984D01*
G01X712736Y86755D02*
X710270Y84289D01*
G01X712736Y90524D02*
Y86755D01*
G01X718707Y96495D02*
X712736Y90524D01*
G01X739336Y96495D02*
X718707D01*
G01X740483Y95348D02*
X739336Y96495D01*
G01X751668Y95348D02*
X740483D01*
G01X753633Y97313D02*
X751668Y95348D01*
G01X766542Y97313D02*
X753633D01*
G01X746781Y81245D02*
X763560Y64466D01*
G01X727885Y81245D02*
X746781D01*
G01X722929Y76289D02*
X727885Y81245D01*
G01X759090Y59820D02*
X763560D01*
G01X754663Y55393D02*
X759090Y59820D01*
G01X727056Y83245D02*
X722100Y78289D01*
G01X747610Y83245D02*
X727056D01*
G01X765560Y65295D02*
X747610Y83245D01*
G01X710422Y57400D02*
X703615D01*
G01X713253Y54569D02*
X710422Y57400D01*
G01X719766Y59400D02*
X702786D01*
G01X726695Y52471D02*
X719766Y59400D01*
G01X709593Y55400D02*
X704825D01*
G01X711253Y53740D02*
X709593Y55400D01*
G01X732339Y63829D02*
X701283D01*
G01X741552Y54616D02*
X732339Y63829D01*
G01X728271Y158979D02*
X729921Y160629D01*
G01X728271Y153646D02*
Y158979D01*
G01X729247Y152670D02*
X728271Y153646D01*
G01X737880Y152670D02*
X729247D01*
G01X742600Y147950D02*
X737880Y152670D01*
G01X749971Y147950D02*
X742600D01*
G01X759596Y138325D02*
X749971Y147950D01*
G01X738352Y175449D02*
Y174615D01*
G01X742467Y179564D02*
X738352Y175449D01*
G01X731592Y156001D02*
X729921Y154330D01*
G01X731592Y164479D02*
Y156001D01*
G01X724756Y171315D02*
X731592Y164479D01*
G01X718850Y171315D02*
X724756D01*
G01X717751Y172414D02*
X718850Y171315D01*
G01X717751Y179405D02*
Y172414D01*
G01X730581Y153670D02*
X729921Y154330D01*
G01X739030Y153670D02*
X730581D01*
G01X742750Y149950D02*
X739030Y153670D01*
G01X750800Y149950D02*
X742750D01*
G01X756850Y143900D02*
X750800Y149950D01*
G01X767429Y143900D02*
X756850D01*
G01X742936Y175365D02*
X748165Y180594D01*
G01X741868Y175365D02*
X742936D01*
G01X738232Y171729D02*
X741868Y175365D01*
G01X735433Y171729D02*
X738232D01*
G01X733783Y170079D02*
X735433Y171729D01*
G01X733070Y170079D02*
X733783D01*
G01X750550Y135200D02*
X771150Y114600D01*
G01X748046Y175363D02*
Y176071D01*
G01X748992Y174417D02*
X748046Y175363D01*
G01X748992Y173711D02*
Y174417D01*
G01X748283Y173002D02*
X748992Y173711D01*
G01X747577Y173002D02*
X748283D01*
G01X746860Y173719D02*
X747577Y173002D01*
G01X746152Y173719D02*
X746860D01*
G01X745445Y173012D02*
X746152Y173719D01*
G01X745445Y172304D02*
Y173012D01*
G01X746162Y171587D02*
X745445Y172304D01*
G01X746162Y170881D02*
Y171587D01*
G01X745360Y170079D02*
X746162Y170881D01*
G01X736219Y170079D02*
X745360D01*
G01X732069Y175378D02*
X729920Y173229D01*
G01X732670Y175378D02*
X732069D01*
G01X735720Y178428D02*
X732670Y175378D01*
G01X708602Y231242D02*
X726879Y249519D01*
G01X708602Y202944D02*
Y231242D01*
G01X704724Y199066D02*
X708602Y202944D01*
G01X704724Y198425D02*
Y199066D01*
G01X707873Y200579D02*
Y198424D01*
G01X713310Y206016D02*
X707873Y200579D01*
G01X713310Y215727D02*
Y206016D01*
G01X712602Y216435D02*
X713310Y215727D01*
G01X712602Y228207D02*
Y216435D01*
G01X721219Y236824D02*
X712602Y228207D01*
G01X721219Y238201D02*
Y236824D01*
G01X743292Y179564D02*
X742467D01*
G01X745912Y182184D02*
X743292Y179564D01*
G01X745912Y182892D02*
Y182184D01*
G01X744972Y183832D02*
X745912Y182892D01*
G01X744972Y184540D02*
Y183832D01*
G01X745679Y185247D02*
X744972Y184540D01*
G01X746387Y185247D02*
X745679D01*
G01X747327Y184307D02*
X746387Y185247D01*
G01X748035Y184307D02*
X747327D01*
G01X748742Y185014D02*
X748035Y184307D01*
G01X748742Y185722D02*
Y185014D01*
G01X747802Y186662D02*
X748742Y185722D01*
G01X747802Y187370D02*
Y186662D01*
G01X748509Y188077D02*
X747802Y187370D01*
G01X749217Y188077D02*
X748509D01*
G01X750157Y187137D02*
X749217Y188077D01*
G01X750865Y187137D02*
X750157D01*
G01X753654Y189926D02*
X750865Y187137D01*
G01X753654Y209756D02*
Y189926D01*
G01X764068Y220170D02*
X753654Y209756D01*
G01X701574Y216325D02*
Y198424D01*
G01X704602Y219353D02*
X701574Y216325D01*
G01X704602Y235943D02*
Y219353D01*
G01X726349Y257690D02*
X704602Y235943D01*
G01X752020Y236480D02*
X754641Y239101D01*
G01X740305Y236480D02*
X752020D01*
G01X738701Y234876D02*
X740305Y236480D01*
G01X737993Y234876D02*
X738701D01*
G01X736348Y236521D02*
X737993Y234876D01*
G01X735640Y236521D02*
X736348D01*
G01X734933Y235814D02*
X735640Y236521D01*
G01X734933Y235106D02*
Y235814D01*
G01X736578Y233461D02*
X734933Y235106D01*
G01X736578Y232753D02*
Y233461D01*
G01X735871Y232046D02*
X736578Y232753D01*
G01X735163Y232046D02*
X735871D01*
G01X733518Y233691D02*
X735163Y232046D01*
G01X732810Y233691D02*
X733518D01*
G01X732103Y232984D02*
X732810Y233691D01*
G01X732103Y232276D02*
Y232984D01*
G01X733748Y230631D02*
X732103Y232276D01*
G01X733748Y229923D02*
Y230631D01*
G01X733041Y229216D02*
X733748Y229923D01*
G01X732333Y229216D02*
X733041D01*
G01X730688Y230861D02*
X732333Y229216D01*
G01X729980Y230861D02*
X730688D01*
G01X729273Y230154D02*
X729980Y230861D01*
G01X729273Y229446D02*
Y230154D01*
G01X730918Y227801D02*
X729273Y229446D01*
G01X730918Y227093D02*
Y227801D01*
G01X730211Y226386D02*
X730918Y227093D01*
G01X729503Y226386D02*
X730211D01*
G01X728367Y227521D02*
X729503Y226386D01*
G01X727661Y227521D02*
X728367D01*
G01X726953Y226813D02*
X727661Y227521D01*
G01X726953Y226107D02*
Y226813D01*
G01X728088Y224971D02*
X726953Y226107D01*
G01X728088Y224263D02*
Y224971D01*
G01X723126Y219301D02*
X728088Y224263D01*
G01X723126Y206428D02*
Y219301D01*
G01X720471Y203773D02*
X723126Y206428D01*
G01X720471Y198424D02*
Y203773D01*
G01X755384Y228274D02*
X765180D01*
G01X754858Y227748D02*
X755384Y228274D01*
G01X754150Y227748D02*
X754858D01*
G01X753606Y228292D02*
X754150Y227748D01*
G01X752898Y228292D02*
X753606D01*
G01X752191Y227585D02*
X752898Y228292D01*
G01X752191Y226877D02*
Y227585D01*
G01X752735Y226333D02*
X752191Y226877D01*
G01X752735Y225625D02*
Y226333D01*
G01X752028Y224918D02*
X752735Y225625D01*
G01X751320Y224918D02*
X752028D01*
G01X750349Y225889D02*
X751320Y224918D01*
G01X749641Y225889D02*
X750349D01*
G01X748934Y225182D02*
X749641Y225889D01*
G01X748934Y224474D02*
Y225182D01*
G01X749905Y223503D02*
X748934Y224474D01*
G01X749905Y222795D02*
Y223503D01*
G01X749198Y222088D02*
X749905Y222795D01*
G01X748490Y222088D02*
X749198D01*
G01X747519Y223059D02*
X748490Y222088D01*
G01X746811Y223059D02*
X747519D01*
G01X746104Y222352D02*
X746811Y223059D01*
G01X746104Y221644D02*
Y222352D01*
G01X747075Y220673D02*
X746104Y221644D01*
G01X747075Y219965D02*
Y220673D01*
G01X746368Y219258D02*
X747075Y219965D01*
G01X745660Y219258D02*
X746368D01*
G01X744689Y220229D02*
X745660Y219258D01*
G01X743981Y220229D02*
X744689D01*
G01X743274Y219522D02*
X743981Y220229D01*
G01X743274Y218814D02*
Y219522D01*
G01X744245Y217843D02*
X743274Y218814D01*
G01X744245Y217135D02*
Y217843D01*
G01X743538Y216428D02*
X744245Y217135D01*
G01X742830Y216428D02*
X743538D01*
G01X741859Y217399D02*
X742830Y216428D01*
G01X741151Y217399D02*
X741859D01*
G01X740444Y216692D02*
X741151Y217399D01*
G01X740444Y215984D02*
Y216692D01*
G01X741415Y215013D02*
X740444Y215984D01*
G01X741415Y214305D02*
Y215013D01*
G01X740708Y213598D02*
X741415Y214305D01*
G01X740000Y213598D02*
X740708D01*
G01X739029Y214569D02*
X740000Y213598D01*
G01X738321Y214569D02*
X739029D01*
G01X737614Y213862D02*
X738321Y214569D01*
G01X737614Y213154D02*
Y213862D01*
G01X738585Y212183D02*
X737614Y213154D01*
G01X738585Y211475D02*
Y212183D01*
G01X737922Y210812D02*
X738585Y211475D01*
G01X737922Y207497D02*
Y210812D01*
G01X734720Y204295D02*
X737922Y207497D01*
G01X734720Y178843D02*
Y204295D01*
G01X732255Y176378D02*
X734720Y178843D01*
G01X729920Y176378D02*
X732255D01*
G01X750328Y232411D02*
X763659D01*
G01X748389Y230472D02*
X750328Y232411D01*
G01X747683Y230472D02*
X748389D01*
G01X746690Y231466D02*
X747683Y230472D01*
G01X745984Y231466D02*
X746690D01*
G01X745275Y230757D02*
X745984Y231466D01*
G01X745275Y230051D02*
Y230757D01*
G01X746268Y229057D02*
X745275Y230051D01*
G01X746268Y228351D02*
Y229057D01*
G01X743449Y225532D02*
X746268Y228351D01*
G01X742741Y225532D02*
X743449D01*
G01X740406Y227867D02*
X742741Y225532D01*
G01X739698Y227867D02*
X740406D01*
G01X738991Y227160D02*
X739698Y227867D01*
G01X738991Y226452D02*
Y227160D01*
G01X741326Y224117D02*
X738991Y226452D01*
G01X741326Y223409D02*
Y224117D01*
G01X740619Y222702D02*
X741326Y223409D01*
G01X739911Y222702D02*
X740619D01*
G01X737576Y225037D02*
X739911Y222702D01*
G01X736868Y225037D02*
X737576D01*
G01X736161Y224330D02*
X736868Y225037D01*
G01X736161Y223622D02*
Y224330D01*
G01X738496Y221287D02*
X736161Y223622D01*
G01X738496Y220579D02*
Y221287D01*
G01X737789Y219872D02*
X738496Y220579D01*
G01X737081Y219872D02*
X737789D01*
G01X734746Y222207D02*
X737081Y219872D01*
G01X734038Y222207D02*
X734746D01*
G01X733331Y221500D02*
X734038Y222207D01*
G01X733331Y220792D02*
Y221500D01*
G01X735666Y218457D02*
X733331Y220792D01*
G01X735666Y217749D02*
Y218457D01*
G01X734959Y217042D02*
X735666Y217749D01*
G01X734251Y217042D02*
X734959D01*
G01X733083Y218211D02*
X734251Y217042D01*
G01X732377Y218211D02*
X733083D01*
G01X731667Y217501D02*
X732377Y218211D01*
G01X731667Y216795D02*
Y217501D01*
G01X732836Y215627D02*
X731667Y216795D01*
G01X732836Y214919D02*
Y215627D01*
G01X731915Y213998D02*
X732836Y214919D01*
G01X731915Y206310D02*
Y213998D01*
G01X725933Y198424D02*
X723621D01*
G01X726433Y198924D02*
X725933Y198424D01*
G01X726433Y201589D02*
Y198924D01*
G01X725933Y202089D02*
X726433Y201589D01*
G01X723943Y202089D02*
X725933D01*
G01X723443Y202589D02*
X723943Y202089D01*
G01X723443Y203589D02*
Y202589D01*
G01X723943Y204089D02*
X723443Y203589D01*
G01X725933Y204089D02*
X723943D01*
G01X726433Y204589D02*
X725933Y204089D01*
G01X726433Y211315D02*
Y204589D01*
G01X726933Y211815D02*
X726433Y211315D01*
G01X728800Y211815D02*
X726933D01*
G01X729300Y212315D02*
X728800Y211815D01*
G01X729300Y213315D02*
Y212315D01*
G01X728800Y213815D02*
X729300Y213315D01*
G01X726933Y213815D02*
X728800D01*
G01X726433Y214315D02*
X726933Y213815D01*
G01X726433Y215315D02*
Y214315D01*
G01X726933Y215815D02*
X726433Y215315D01*
G01X729008Y215815D02*
X726933D01*
G01X729508Y216315D02*
X729008Y215815D01*
G01X729508Y217315D02*
Y216315D01*
G01X729008Y217815D02*
X729508Y217315D01*
G01X726933Y217815D02*
X729008D01*
G01X726433Y218315D02*
X726933Y217815D01*
G01X726433Y219315D02*
Y218315D01*
G01X726933Y219815D02*
X726433Y219315D01*
G01X728725Y219815D02*
X726933D01*
G01X743390Y234480D02*
X728725Y219815D01*
G01X755164Y234480D02*
X743390D01*
G01X755664Y234980D02*
X755164Y234480D01*
G01X755664Y236538D02*
Y234980D01*
G01X756164Y237038D02*
X755664Y236538D01*
G01X757164Y237038D02*
X756164D01*
G01X757664Y236538D02*
X757164Y237038D01*
G01X757664Y234980D02*
Y236538D01*
G01X758164Y234480D02*
X757664Y234980D01*
G01X759164Y234480D02*
X758164D01*
G01X759664Y234980D02*
X759164Y234480D01*
G01X718972Y180626D02*
X717751Y179405D01*
G01X718972Y184349D02*
Y180626D01*
G01X717567Y185754D02*
X718972Y184349D01*
G01X717567Y193884D02*
Y185754D01*
G01X715009Y196442D02*
X717567Y193884D01*
G01X699980Y196442D02*
X715009D01*
G01X751654Y210585D02*
X763273Y222204D01*
G01X751654Y206755D02*
Y210585D01*
G01X751154Y206255D02*
X751654Y206755D01*
G01X744512Y206255D02*
X751154D01*
G01X744012Y205755D02*
X744512Y206255D01*
G01X744012Y204755D02*
Y205755D01*
G01X744512Y204255D02*
X744012Y204755D01*
G01X751154Y204255D02*
X744512D01*
G01X751654Y203755D02*
X751154Y204255D01*
G01X751654Y202755D02*
Y203755D01*
G01X751154Y202255D02*
X751654Y202755D01*
G01X747804Y202255D02*
X751154D01*
G01X747304Y201755D02*
X747804Y202255D01*
G01X747304Y200755D02*
Y201755D01*
G01X747804Y200255D02*
X747304Y200755D01*
G01X751154Y200255D02*
X747804D01*
G01X751654Y199755D02*
X751154Y200255D01*
G01X751654Y198755D02*
Y199755D01*
G01X751154Y198255D02*
X751654Y198755D01*
G01X748722Y198255D02*
X751154D01*
G01X748222Y197755D02*
X748722Y198255D01*
G01X748222Y196755D02*
Y197755D01*
G01X748722Y196255D02*
X748222Y196755D01*
G01X751154Y196255D02*
X748722D01*
G01X751654Y195755D02*
X751154Y196255D01*
G01X751654Y194755D02*
Y195755D01*
G01X751154Y194255D02*
X751654Y194755D01*
G01X748722Y194255D02*
X751154D01*
G01X748222Y193755D02*
X748722Y194255D01*
G01X748222Y192755D02*
Y193755D01*
G01X748722Y192255D02*
X748222Y192755D01*
G01X751154Y192255D02*
X748722D01*
G01X751654Y191755D02*
X751154Y192255D01*
G01X751654Y190755D02*
Y191755D01*
G01X751154Y190255D02*
X751654Y190755D01*
G01X744552Y190255D02*
X751154D01*
G01X744052Y190755D02*
X744552Y190255D01*
G01X744052Y193784D02*
Y190755D01*
G01X726114Y237319D02*
X726821Y238026D01*
G01X725406Y237319D02*
X726114D01*
G01X724669Y238056D02*
X725406Y237319D01*
G01X723254Y237349D02*
X723961Y238056D01*
G01X723254Y236641D02*
Y237349D01*
G01X723991Y235904D02*
X723254Y236641D01*
G01X723991Y235196D02*
Y235904D01*
G01X717236Y228441D02*
X723991Y235196D01*
G01X717236Y225845D02*
Y228441D01*
G01X716736Y225345D02*
X717236Y225845D01*
G01X715211Y225345D02*
X716736D01*
G01X714711Y224845D02*
X715211Y225345D01*
G01X714711Y223845D02*
Y224845D01*
G01X715211Y223345D02*
X714711Y223845D01*
G01X716525Y223345D02*
X715211D01*
G01X717025Y222845D02*
X716525Y223345D01*
G01X717025Y219093D02*
Y222845D01*
G01X716525Y218593D02*
X717025Y219093D01*
G01X715503Y218593D02*
X716525D01*
G01X715003Y218093D02*
X715503Y218593D01*
G01X715003Y217093D02*
Y218093D01*
G01X715503Y216593D02*
X715003Y217093D01*
G01X716441Y216593D02*
X715503D01*
G01X716941Y216093D02*
X716441Y216593D01*
G01X716941Y215093D02*
Y216093D01*
G01X716441Y214593D02*
X716941Y215093D01*
G01X715503Y214593D02*
X716441D01*
G01X715003Y214093D02*
X715503Y214593D01*
G01X715003Y213093D02*
Y214093D01*
G01X715503Y212593D02*
X715003Y213093D01*
G01X716736Y212593D02*
X715503D01*
G01X717236Y212093D02*
X716736Y212593D01*
G01X717236Y209942D02*
Y212093D01*
G01X714817Y207523D02*
X717236Y209942D01*
G01X714817Y205046D02*
Y207523D01*
G01X711023Y201252D02*
X714817Y205046D01*
G01X711023Y198425D02*
Y201252D01*
G01X717322Y203353D02*
Y198425D01*
G01X716680Y203995D02*
X717322Y203353D01*
G01X716680Y206355D02*
Y203995D01*
G01X719046Y208721D02*
X716680Y206355D01*
G01X719046Y211967D02*
Y208721D01*
G01X719546Y212467D02*
X719046Y211967D01*
G01X720422Y212467D02*
X719546D01*
G01X720922Y212967D02*
X720422Y212467D01*
G01X720922Y213967D02*
Y212967D01*
G01X720422Y214467D02*
X720922Y213967D01*
G01X719546Y214467D02*
X720422D01*
G01X719046Y214967D02*
X719546Y214467D01*
G01X719046Y215967D02*
Y214967D01*
G01X719546Y216467D02*
X719046Y215967D01*
G01X720422Y216467D02*
X719546D01*
G01X720922Y216967D02*
X720422Y216467D01*
G01X720922Y217967D02*
Y216967D01*
G01X720422Y218467D02*
X720922Y217967D01*
G01X719546Y218467D02*
X720422D01*
G01X719046Y218967D02*
X719546Y218467D01*
G01X719046Y222615D02*
Y218967D01*
G01X721597Y225166D02*
X719046Y222615D01*
G01X721597Y225956D02*
Y225166D01*
G01X719971Y227582D02*
X721597Y225956D01*
G01X719971Y228311D02*
Y227582D01*
G01X720678Y229018D02*
X719971Y228311D01*
G01X721386Y229018D02*
X720678D01*
G01X723605Y226799D02*
X721386Y229018D01*
G01X724313Y226799D02*
X723605D01*
G01X725020Y227506D02*
X724313Y226799D01*
G01X725020Y228214D02*
Y227506D01*
G01X722801Y230433D02*
X725020Y228214D01*
G01X722801Y231141D02*
Y230433D01*
G01X723508Y231848D02*
X722801Y231141D01*
G01X724216Y231848D02*
X723508D01*
G01X724737Y231327D02*
X724216Y231848D01*
G01X725445Y231327D02*
X724737D01*
G01X728887Y234769D02*
X725445Y231327D01*
G01X728887Y235966D02*
Y234769D01*
G01X731822Y238901D02*
X728887Y235966D01*
G01X755654Y207756D02*
X760248Y212350D01*
G01X755654Y188083D02*
Y207756D01*
G01X753116Y185545D02*
X755654Y188083D01*
G01X753116Y184839D02*
Y185545D01*
G01X754850Y183104D02*
X753116Y184839D01*
G01X754850Y182398D02*
Y183104D01*
G01X754141Y181689D02*
X754850Y182398D01*
G01X753435Y181689D02*
X754141D01*
G01X751701Y183424D02*
X753435Y181689D01*
G01X750995Y183424D02*
X751701D01*
G01X750286Y182715D02*
X750995Y183424D01*
G01X750286Y182009D02*
Y182715D01*
G01X752020Y180274D02*
X750286Y182009D01*
G01X752020Y179568D02*
Y180274D01*
G01X751311Y178859D02*
X752020Y179568D01*
G01X750605Y178859D02*
X751311D01*
G01X748871Y180594D02*
X750605Y178859D01*
G01X748165Y180594D02*
X748871D01*
G01X757654Y204398D02*
X768810Y215554D01*
G01X757654Y182373D02*
Y204398D01*
G01X751113Y175832D02*
X757654Y182373D01*
G01X750407Y175832D02*
X751113D01*
G01X749461Y176778D02*
X750407Y175832D01*
G01X748753Y176778D02*
X749461D01*
G01X748046Y176071D02*
X748753Y176778D01*
G01X751088Y230342D02*
X764419D01*
G01X735215Y214469D02*
X751088Y230342D01*
G01X735215Y209458D02*
Y214469D01*
G01X733565Y207808D02*
X735215Y209458D01*
G01X733565Y183171D02*
Y207808D01*
G01X729921Y179527D02*
X733565Y183171D01*
G01X705336Y217258D02*
Y208437D01*
G01X706602Y218524D02*
X705336Y217258D01*
G01X706602Y232071D02*
Y218524D01*
G01X728176Y253645D02*
X706602Y232071D01*
G01X756972Y224204D02*
X769602D01*
G01X756097Y223329D02*
X756972Y224204D01*
G01X756097Y222621D02*
Y223329D01*
G01X758069Y220649D02*
X756097Y222621D01*
G01X758069Y219941D02*
Y220649D01*
G01X757362Y219234D02*
X758069Y219941D01*
G01X756654Y219234D02*
X757362D01*
G01X754682Y221206D02*
X756654Y219234D01*
G01X753974Y221206D02*
X754682D01*
G01X753267Y220499D02*
X753974Y221206D01*
G01X753267Y219791D02*
Y220499D01*
G01X755239Y217819D02*
X753267Y219791D01*
G01X755239Y217111D02*
Y217819D01*
G01X754532Y216404D02*
X755239Y217111D01*
G01X753824Y216404D02*
X754532D01*
G01X751852Y218376D02*
X753824Y216404D01*
G01X751144Y218376D02*
X751852D01*
G01X750437Y217669D02*
X751144Y218376D01*
G01X750437Y216961D02*
Y217669D01*
G01X752409Y214989D02*
X750437Y216961D01*
G01X752409Y214281D02*
Y214989D01*
G01X751702Y213574D02*
X752409Y214281D01*
G01X750994Y213574D02*
X751702D01*
G01X749022Y215546D02*
X750994Y213574D01*
G01X748314Y215546D02*
X749022D01*
G01X747607Y214839D02*
X748314Y215546D01*
G01X747607Y214131D02*
Y214839D01*
G01X749382Y212356D02*
X747607Y214131D01*
G01X749382Y211648D02*
Y212356D01*
G01X748675Y210941D02*
X749382Y211648D01*
G01X747967Y210941D02*
X748675D01*
G01X746192Y212716D02*
X747967Y210941D01*
G01X745484Y212716D02*
X746192D01*
G01X744777Y212009D02*
X745484Y212716D01*
G01X744777Y211301D02*
Y212009D01*
G01X746339Y209739D02*
X744777Y211301D01*
G01X746339Y209033D02*
Y209739D01*
G01X745629Y208325D02*
X746339Y209033D01*
G01X744923Y208325D02*
X745629D01*
G01X743362Y209886D02*
X744923Y208325D01*
G01X742654Y209886D02*
X743362D01*
G01X742085Y209317D02*
X742654Y209886D01*
G01X742085Y189396D02*
Y209317D01*
G01X741585Y188896D02*
X742085Y189396D01*
G01X739355Y188896D02*
X741585D01*
G01X738855Y188396D02*
X739355Y188896D01*
G01X738855Y187396D02*
Y188396D01*
G01X739355Y186896D02*
X738855Y187396D01*
G01X741585Y186896D02*
X739355D01*
G01X742085Y186396D02*
X741585Y186896D01*
G01X742085Y184715D02*
Y186396D01*
G01X741585Y184215D02*
X742085Y184715D01*
G01X738952Y184215D02*
X741585D01*
G01X711310Y214017D02*
Y207023D01*
G01X710602Y214725D02*
X711310Y214017D01*
G01X710602Y230413D02*
Y214725D01*
G01X725443Y245254D02*
X710602Y230413D01*
G01X735720Y197917D02*
Y178428D01*
G01X740489Y202686D02*
X735720Y197917D01*
G01X740489Y210550D02*
Y202686D01*
G01X756213Y226274D02*
X740489Y210550D01*
G01X768843Y226274D02*
X756213D01*
G01X754411Y251499D02*
X760679Y257767D01*
G01X751994Y251499D02*
X754411D01*
G01X750014Y249519D02*
X751994Y251499D01*
G01X748012Y249519D02*
X750014D01*
G01X747512Y250019D02*
X748012Y249519D01*
G01X747512Y251104D02*
Y250019D01*
G01X747012Y251604D02*
X747512Y251104D01*
G01X746012Y251604D02*
X747012D01*
G01X745512Y251104D02*
X746012Y251604D01*
G01X745512Y250019D02*
Y251104D01*
G01X745012Y249519D02*
X745512Y250019D01*
G01X740813Y249519D02*
X745012D01*
G01X740313Y250019D02*
X740813Y249519D01*
G01X740313Y251033D02*
Y250019D01*
G01X739813Y251533D02*
X740313Y251033D01*
G01X738813Y251533D02*
X739813D01*
G01X738313Y251033D02*
X738813Y251533D01*
G01X738313Y250019D02*
Y251033D01*
G01X737813Y249519D02*
X738313Y250019D01*
G01X736813Y249519D02*
X737813D01*
G01X736313Y250019D02*
X736813Y249519D01*
G01X736313Y251033D02*
Y250019D01*
G01X735813Y251533D02*
X736313Y251033D01*
G01X734813Y251533D02*
X735813D01*
G01X734313Y251033D02*
X734813Y251533D01*
G01X734313Y250019D02*
Y251033D01*
G01X733813Y249519D02*
X734313Y250019D01*
G01X732813Y249519D02*
X733813D01*
G01X732313Y250019D02*
X732813Y249519D01*
G01X732313Y251033D02*
Y250019D01*
G01X731813Y251533D02*
X732313Y251033D01*
G01X730813Y251533D02*
X731813D01*
G01X730313Y251033D02*
X730813Y251533D01*
G01X730313Y250019D02*
Y251033D01*
G01X729813Y249519D02*
X730313Y250019D01*
G01X726879Y249519D02*
X729813D01*
G01X725958Y242940D02*
X721219Y238201D01*
G01X749582Y242940D02*
X725958D01*
G01X753732Y247090D02*
X749582Y242940D01*
G01X755923Y247090D02*
X753732D01*
G01X758564Y249731D02*
X755923Y247090D01*
G01X765392Y249731D02*
X758564D01*
G01X714900Y249800D02*
X701046D01*
G01X742700Y277600D02*
X714900Y249800D01*
G01X742700Y297200D02*
Y277600D01*
G01X752983Y307483D02*
X742700Y297200D01*
G01X753843Y257690D02*
X726349D01*
G01X755693Y259540D02*
X753843Y257690D01*
G01X754641Y239101D02*
X764691D01*
G01X754548Y244877D02*
X759778D01*
G01X750572Y240901D02*
X754548Y244877D01*
G01X729696Y240901D02*
X750572D01*
G01X728944Y240149D02*
X729696Y240901D01*
G01X728236Y240149D02*
X728944D01*
G01X727499Y240886D02*
X728236Y240149D01*
G01X726791Y240886D02*
X727499D01*
G01X726084Y240179D02*
X726791Y240886D01*
G01X726084Y239471D02*
Y240179D01*
G01X726821Y238734D02*
X726084Y239471D01*
G01X726821Y238026D02*
Y238734D01*
G01X723961Y238056D02*
X724669D01*
G01X751401Y238901D02*
X731822D01*
G01X755377Y242877D02*
X751401Y238901D01*
G01X761810Y242877D02*
X755377D01*
G01X752627Y253645D02*
X728176D01*
G01X759415Y260433D02*
X752627Y253645D01*
G01X773028Y275583D02*
X759415Y261970D01*
G01X748883Y245254D02*
X725443D01*
G01X752772Y249143D02*
X748883Y245254D01*
G01X754969Y249143D02*
X752772D01*
G01X759257Y253431D02*
X754969Y249143D01*
G01X766263Y253431D02*
X759257D01*
G01X752983Y414815D02*
Y307483D01*
G01X746828Y312328D02*
Y415312D01*
G01X749200Y415769D02*
Y311756D01*
G01X745748Y422050D02*
X752983Y414815D01*
G01X716301Y422050D02*
X745748D01*
G01X709632Y428719D02*
X716301Y422050D01*
G01X702604Y418050D02*
X698738Y421916D01*
G01X744090Y418050D02*
X702604D01*
G01X746828Y415312D02*
X744090Y418050D01*
G01X744919Y420050D02*
X749200Y415769D01*
G01X713439Y420050D02*
X744919D01*
G01X706770Y426719D02*
X713439Y420050D01*
G01X700855Y426719D02*
X706770D01*
G01X767560Y33703D02*
Y66124D01*
G01X765560Y37215D02*
Y65295D01*
G01X778450Y106230D02*
Y127867D01*
G01X767533Y95313D02*
X778450Y106230D01*
G01X780450Y105401D02*
Y130879D01*
G01X768362Y93313D02*
X780450Y105401D01*
G01X771150Y101921D02*
X766542Y97313D01*
G01X771150Y114600D02*
Y101921D01*
G01X763560Y64466D02*
Y59820D01*
G01X767992Y138325D02*
X759596D01*
G01X778450Y127867D02*
X767992Y138325D01*
G01X780450Y130879D02*
X767429Y143900D01*
G01X771820Y220170D02*
X764068D01*
G01X788687Y237037D02*
X771820Y220170D01*
G01X788687Y239685D02*
Y237037D01*
G01X765180Y228274D02*
X784837Y247931D01*
G01X763659Y232411D02*
X780837Y249589D01*
G01X759664Y236538D02*
Y234980D01*
G01X760164Y237038D02*
X759664Y236538D01*
G01X761164Y237038D02*
X760164D01*
G01X761664Y236538D02*
X761164Y237038D01*
G01X761664Y234980D02*
Y236538D01*
G01X762164Y234480D02*
X761664Y234980D01*
G01X762899Y234480D02*
X762164D01*
G01X778837Y250418D02*
X762899Y234480D01*
G01X770431Y222204D02*
X786687Y238460D01*
G01X763273Y222204D02*
X770431D01*
G01X773770Y217715D02*
X797702Y241647D01*
G01X767066Y217715D02*
X773770D01*
G01X761701Y212350D02*
X767066Y217715D01*
G01X760248Y212350D02*
X761701D01*
G01X774526Y215554D02*
X799702Y240730D01*
G01X768810Y215554D02*
X774526D01*
G01X764419Y230342D02*
X782837Y248760D01*
G01X769602Y224204D02*
X784687Y239289D01*
G01X771656Y229087D02*
X768843Y226274D01*
G01X771656Y229793D02*
Y229087D01*
G01X770998Y230450D02*
X771656Y229793D01*
G01X770998Y231156D02*
Y230450D01*
G01X771707Y231865D02*
X770998Y231156D01*
G01X772413Y231865D02*
X771707D01*
G01X773071Y231208D02*
X772413Y231865D01*
G01X773777Y231208D02*
X773071D01*
G01X774486Y231917D02*
X773777Y231208D01*
G01X774486Y232623D02*
Y231917D01*
G01X773828Y233280D02*
X774486Y232623D01*
G01X773828Y233986D02*
Y233280D01*
G01X774537Y234695D02*
X773828Y233986D01*
G01X775243Y234695D02*
X774537D01*
G01X775901Y234038D02*
X775243Y234695D01*
G01X776607Y234038D02*
X775901D01*
G01X777316Y234747D02*
X776607Y234038D01*
G01X777316Y235453D02*
Y234747D01*
G01X776658Y236110D02*
X777316Y235453D01*
G01X776658Y236816D02*
Y236110D01*
G01X777367Y237525D02*
X776658Y236816D01*
G01X778731Y236868D02*
X778073Y237525D01*
G01X779437Y236868D02*
X778731D01*
G01X782687Y240118D02*
X779437Y236868D01*
G01X763506Y257767D02*
X765638Y255635D01*
G01X760679Y257767D02*
X763506D01*
G01X772637Y256976D02*
X765392Y249731D01*
G01X772637Y268372D02*
Y256976D01*
G01X774026Y269761D02*
X772637Y268372D01*
G01X782837Y269761D02*
X774026D01*
G01X784837Y271761D02*
X782837Y269761D01*
G01X793610Y244608D02*
X788687Y239685D01*
G01X793610Y248227D02*
Y244608D01*
G01X795702Y250319D02*
X793610Y248227D01*
G01X795702Y257236D02*
Y250319D01*
G01X791987Y260951D02*
X795702Y257236D01*
G01X791987Y268593D02*
Y260951D01*
G01X793155Y269761D02*
X791987Y268593D01*
G01X794454Y269761D02*
X793155D01*
G01X795687Y270994D02*
X794454Y269761D01*
G01X795687Y273846D02*
Y270994D01*
G01X793837Y275696D02*
X795687Y273846D01*
G01X776837Y263826D02*
X780837Y267826D01*
G01X776837Y251247D02*
Y263826D01*
G01X764691Y239101D02*
X776837Y251247D01*
G01X784837Y247931D02*
Y259951D01*
G01X783331Y263891D02*
X784837D01*
G01X780837Y261397D02*
X783331Y263891D01*
G01X780837Y249589D02*
Y261397D01*
G01X778837Y262226D02*
Y250418D01*
G01X784437Y267826D02*
X778837Y262226D01*
G01X784837Y267826D02*
X784437D01*
G01X791700Y252076D02*
X793852D01*
G01X791200Y251576D02*
X791700Y252076D01*
G01X791200Y245027D02*
Y251576D01*
G01X786687Y240514D02*
X791200Y245027D01*
G01X786687Y238460D02*
Y240514D01*
G01X766302Y247644D02*
X774657Y255999D01*
G01X762545Y247644D02*
X766302D01*
G01X759778Y244877D02*
X762545Y247644D01*
G01X762310Y243377D02*
X761810Y242877D01*
G01X762310Y244434D02*
Y243377D01*
G01X762810Y244934D02*
X762310Y244434D01*
G01X763810Y244934D02*
X762810D01*
G01X764310Y244434D02*
X763810Y244934D01*
G01X764310Y243377D02*
Y244434D01*
G01X764810Y242877D02*
X764310Y243377D01*
G01X765638Y242877D02*
X764810D01*
G01X774637Y251876D02*
X765638Y242877D01*
G01X795500Y262033D02*
X793837Y263696D01*
G01X795500Y260267D02*
Y262033D01*
G01X797702Y258065D02*
X795500Y260267D01*
G01X797702Y241647D02*
Y258065D01*
G01X797500Y264163D02*
X793837Y267826D01*
G01X797500Y261096D02*
Y264163D01*
G01X799702Y258894D02*
X797500Y261096D01*
G01X799702Y240730D02*
Y258894D01*
G01X788296Y279636D02*
X793837D01*
G01X787796Y279136D02*
X788296Y279636D01*
G01X787796Y278136D02*
Y279136D01*
G01X788296Y277636D02*
X787796Y278136D01*
G01X789922Y277636D02*
X788296D01*
G01X790422Y277136D02*
X789922Y277636D01*
G01X790422Y276136D02*
Y277136D01*
G01X789922Y275636D02*
X790422Y276136D01*
G01X788171Y275636D02*
X789922D01*
G01X787671Y275136D02*
X788171Y275636D01*
G01X787671Y262391D02*
Y275136D01*
G01X787171Y261891D02*
X787671Y262391D01*
G01X784160Y261891D02*
X787171D01*
G01X782837Y260568D02*
X784160Y261891D01*
G01X782837Y248760D02*
Y260568D01*
G01X759415Y261970D02*
Y260433D01*
G01X781344Y275583D02*
X773028D01*
G01X793457Y287696D02*
X781344Y275583D01*
G01X793837Y287696D02*
X793457D01*
G01X789700Y256011D02*
X793852D01*
G01X789200Y255511D02*
X789700Y256011D01*
G01X789200Y245856D02*
Y255511D01*
G01X784687Y241343D02*
X789200Y245856D01*
G01X784687Y239289D02*
Y241343D01*
G01X768787Y255955D02*
X766263Y253431D01*
G01X768787Y268513D02*
Y255955D01*
G01X772035Y271761D02*
X768787Y268513D01*
G01X780837Y271761D02*
X772035D01*
G01X778073Y237525D02*
X777367D01*
G01X782687Y242592D02*
Y240118D01*
G01X786837Y246742D02*
X782687Y242592D01*
G01X786837Y256877D02*
Y246742D01*
G01X789829Y259869D02*
X786837Y256877D01*
G01X789829Y269264D02*
Y259869D01*
G01X792326Y271761D02*
X789829Y269264D01*
G01X793837Y271761D02*
X792326D01*
G54D12*
G01X6250Y-135162D02*
Y-152662D01*
G01X1228Y-135162D02*
X11272D01*
G01X20038Y-152662D02*
Y-135162D01*
G01Y-143620D02*
X21130Y-142162D01*
X22222Y-141287D01*
X23968Y-140996D01*
X25278Y-141287D01*
X26807Y-142454D01*
X27462Y-144204D01*
Y-152662D01*
G01X41250Y-140996D02*
Y-152662D01*
G01Y-136329D02*
X40813Y-136037D01*
Y-135454D01*
X41250Y-135162D01*
X41687Y-135454D01*
Y-136037D01*
X41250Y-136329D01*
G01X55475Y-150621D02*
X56567Y-151787D01*
X58095Y-152662D01*
X59405D01*
X60715Y-152079D01*
X61588Y-151204D01*
X62025Y-150038D01*
X61807Y-148287D01*
X60933Y-147412D01*
X57003Y-145662D01*
X56130Y-143620D01*
X56567Y-142162D01*
X57440Y-141287D01*
X58750Y-140996D01*
X60060Y-141287D01*
X61370Y-142162D01*
G01X90693Y-157037D02*
X92222Y-158204D01*
X93968Y-158495D01*
X95496Y-158204D01*
X96807Y-156746D01*
X97680Y-154704D01*
Y-140996D01*
G01Y-143329D02*
X96807Y-142162D01*
X95496Y-141287D01*
X93968Y-140996D01*
X92222Y-141579D01*
X91130Y-142745D01*
X90256Y-144787D01*
X89820Y-146829D01*
X90038Y-148579D01*
X90912Y-150621D01*
X92222Y-152079D01*
X93968Y-152662D01*
X95278Y-152370D01*
X96807Y-151204D01*
X97680Y-150038D01*
G01X107975Y-144787D02*
X114962D01*
X114307Y-142745D01*
X113215Y-141579D01*
X111687Y-140996D01*
X110158Y-141287D01*
X108848Y-142162D01*
X107975Y-144204D01*
X107538Y-145954D01*
Y-147704D01*
X107975Y-149454D01*
X109067Y-151204D01*
X110377Y-152370D01*
X111905Y-152662D01*
X113433Y-152079D01*
X114962Y-150329D01*
G01X125693Y-152662D02*
Y-140996D01*
G01Y-143329D02*
X126785Y-142162D01*
X127877Y-141287D01*
X129405Y-140996D01*
X130496Y-141287D01*
X131807Y-142162D01*
G01X142320Y-152662D02*
Y-135162D01*
G01Y-143912D02*
X143412Y-142162D01*
X144722Y-141287D01*
X146032Y-140996D01*
X147996Y-141579D01*
X149307Y-142745D01*
X150180Y-144787D01*
Y-147120D01*
X149743Y-149454D01*
X148870Y-151204D01*
X147342Y-152370D01*
X146032Y-152662D01*
X144722Y-152370D01*
X143412Y-151496D01*
X142320Y-150038D01*
G01X160475Y-144787D02*
X167462D01*
X166807Y-142745D01*
X165715Y-141579D01*
X164187Y-140996D01*
X162658Y-141287D01*
X161348Y-142162D01*
X160475Y-144204D01*
X160038Y-145954D01*
Y-147704D01*
X160475Y-149454D01*
X161567Y-151204D01*
X162877Y-152370D01*
X164405Y-152662D01*
X165933Y-152079D01*
X167462Y-150329D01*
G01X178193Y-152662D02*
Y-140996D01*
G01Y-143329D02*
X179285Y-142162D01*
X180377Y-141287D01*
X181905Y-140996D01*
X182996Y-141287D01*
X184307Y-142162D01*
G01X216250Y-140996D02*
Y-152662D01*
G01Y-136329D02*
X215813Y-136037D01*
Y-135454D01*
X216250Y-135162D01*
X216687Y-135454D01*
Y-136037D01*
X216250Y-136329D01*
G01X230475Y-150621D02*
X231567Y-151787D01*
X233095Y-152662D01*
X234405D01*
X235715Y-152079D01*
X236588Y-151204D01*
X237025Y-150038D01*
X236807Y-148287D01*
X235933Y-147412D01*
X232003Y-145662D01*
X231130Y-143620D01*
X231567Y-142162D01*
X232440Y-141287D01*
X233750Y-140996D01*
X235060Y-141287D01*
X236370Y-142162D01*
G01X265256Y-157037D02*
X266785Y-158204D01*
X268095Y-158495D01*
X269842Y-157912D01*
X271152Y-156454D01*
X271807Y-153828D01*
Y-140996D01*
G01Y-136329D02*
X271370Y-136037D01*
Y-135454D01*
X271807Y-135162D01*
X272243Y-135454D01*
Y-136037D01*
X271807Y-136329D01*
G01X282538Y-140996D02*
Y-149162D01*
X283412Y-151204D01*
X284722Y-152370D01*
X286250Y-152662D01*
X287778Y-152370D01*
X289088Y-151204D01*
X289962Y-149162D01*
G01Y-152662D02*
Y-140996D01*
G01X300475Y-150621D02*
X301567Y-151787D01*
X303095Y-152662D01*
X304405D01*
X305715Y-152079D01*
X306588Y-151204D01*
X307025Y-150038D01*
X306807Y-148287D01*
X305933Y-147412D01*
X302003Y-145662D01*
X301130Y-143620D01*
X301567Y-142162D01*
X302440Y-141287D01*
X303750Y-140996D01*
X305060Y-141287D01*
X306370Y-142162D01*
G01X321250Y-135162D02*
Y-152662D01*
G01X318193Y-140996D02*
X324307D01*
G01X354940Y-152662D02*
Y-137787D01*
X355377Y-136329D01*
X356250Y-135454D01*
X357560Y-135162D01*
X358870Y-135745D01*
X359525Y-137204D01*
G01X356905Y-142162D02*
X352538D01*
G01X373750Y-152662D02*
X372440Y-152370D01*
X371130Y-151204D01*
X370256Y-149162D01*
X369820Y-146829D01*
X370256Y-144495D01*
X371130Y-142454D01*
X372440Y-141287D01*
X373750Y-140996D01*
X375060Y-141287D01*
X376370Y-142454D01*
X377243Y-144495D01*
X377462Y-146829D01*
X377243Y-149162D01*
X376370Y-151204D01*
X375060Y-152370D01*
X373750Y-152662D01*
G01X388193D02*
Y-140996D01*
G01Y-143329D02*
X389285Y-142162D01*
X390377Y-141287D01*
X391905Y-140996D01*
X392996Y-141287D01*
X394307Y-142162D01*
G01X421665Y-157912D02*
X422975Y-158495D01*
X424722Y-157912D01*
X425813Y-156746D01*
X426687Y-155287D01*
X427996Y-150621D01*
X430835Y-140996D01*
G01X423848D02*
X427996Y-150621D01*
G01X443750Y-152662D02*
X442440Y-152370D01*
X441130Y-151204D01*
X440256Y-149162D01*
X439820Y-146829D01*
X440256Y-144495D01*
X441130Y-142454D01*
X442440Y-141287D01*
X443750Y-140996D01*
X445060Y-141287D01*
X446370Y-142454D01*
X447243Y-144495D01*
X447462Y-146829D01*
X447243Y-149162D01*
X446370Y-151204D01*
X445060Y-152370D01*
X443750Y-152662D01*
G01X457538Y-140996D02*
Y-149162D01*
X458412Y-151204D01*
X459722Y-152370D01*
X461250Y-152662D01*
X462778Y-152370D01*
X464088Y-151204D01*
X464962Y-149162D01*
G01Y-152662D02*
Y-140996D01*
G01X475693Y-152662D02*
Y-140996D01*
G01Y-143329D02*
X476785Y-142162D01*
X477877Y-141287D01*
X479405Y-140996D01*
X480496Y-141287D01*
X481807Y-142162D01*
G01X510693Y-152662D02*
Y-140996D01*
G01Y-143329D02*
X511785Y-142162D01*
X512877Y-141287D01*
X514405Y-140996D01*
X515496Y-141287D01*
X516807Y-142162D01*
G01X527975Y-144787D02*
X534962D01*
X534307Y-142745D01*
X533215Y-141579D01*
X531687Y-140996D01*
X530158Y-141287D01*
X528848Y-142162D01*
X527975Y-144204D01*
X527538Y-145954D01*
Y-147704D01*
X527975Y-149454D01*
X529067Y-151204D01*
X530377Y-152370D01*
X531905Y-152662D01*
X533433Y-152079D01*
X534962Y-150329D01*
G01X547440Y-152662D02*
Y-137787D01*
X547877Y-136329D01*
X548750Y-135454D01*
X550060Y-135162D01*
X551370Y-135745D01*
X552025Y-137204D01*
G01X549405Y-142162D02*
X545038D01*
G01X562975Y-144787D02*
X569962D01*
X569307Y-142745D01*
X568215Y-141579D01*
X566687Y-140996D01*
X565158Y-141287D01*
X563848Y-142162D01*
X562975Y-144204D01*
X562538Y-145954D01*
Y-147704D01*
X562975Y-149454D01*
X564067Y-151204D01*
X565377Y-152370D01*
X566905Y-152662D01*
X568433Y-152079D01*
X569962Y-150329D01*
G01X580693Y-152662D02*
Y-140996D01*
G01Y-143329D02*
X581785Y-142162D01*
X582877Y-141287D01*
X584405Y-140996D01*
X585496Y-141287D01*
X586807Y-142162D01*
G01X597975Y-144787D02*
X604962D01*
X604307Y-142745D01*
X603215Y-141579D01*
X601687Y-140996D01*
X600158Y-141287D01*
X598848Y-142162D01*
X597975Y-144204D01*
X597538Y-145954D01*
Y-147704D01*
X597975Y-149454D01*
X599067Y-151204D01*
X600377Y-152370D01*
X601905Y-152662D01*
X603433Y-152079D01*
X604962Y-150329D01*
G01X615038Y-152662D02*
Y-140996D01*
G01Y-143912D02*
X615912Y-142454D01*
X617222Y-141287D01*
X618968Y-140996D01*
X620496Y-141287D01*
X621807Y-142454D01*
X622462Y-144495D01*
Y-152662D01*
G01X639743Y-142454D02*
X638215Y-141287D01*
X636905Y-140996D01*
X635158Y-141579D01*
X633848Y-142745D01*
X632975Y-144787D01*
X632756Y-146829D01*
X632975Y-148871D01*
X633848Y-150621D01*
X635158Y-152079D01*
X636905Y-152662D01*
X638433Y-152079D01*
X639743Y-150912D01*
G01X650475Y-144787D02*
X657462D01*
X656807Y-142745D01*
X655715Y-141579D01*
X654187Y-140996D01*
X652658Y-141287D01*
X651348Y-142162D01*
X650475Y-144204D01*
X650038Y-145954D01*
Y-147704D01*
X650475Y-149454D01*
X651567Y-151204D01*
X652877Y-152370D01*
X654405Y-152662D01*
X655933Y-152079D01*
X657462Y-150329D01*
G01X688750Y-135162D02*
Y-152662D01*
G01X685693Y-140996D02*
X691807D01*
G01X706250Y-152662D02*
X704940Y-152370D01*
X703630Y-151204D01*
X702756Y-149162D01*
X702320Y-146829D01*
X702756Y-144495D01*
X703630Y-142454D01*
X704940Y-141287D01*
X706250Y-140996D01*
X707560Y-141287D01*
X708870Y-142454D01*
X709743Y-144495D01*
X709962Y-146829D01*
X709743Y-149162D01*
X708870Y-151204D01*
X707560Y-152370D01*
X706250Y-152662D01*
G01X739940D02*
Y-137787D01*
X740377Y-136329D01*
X741250Y-135454D01*
X742560Y-135162D01*
X743870Y-135745D01*
X744525Y-137204D01*
G01X741905Y-142162D02*
X737538D01*
G01X758750Y-140996D02*
Y-152662D01*
G01Y-136329D02*
X758313Y-136037D01*
Y-135454D01*
X758750Y-135162D01*
X759187Y-135454D01*
Y-136037D01*
X758750Y-136329D01*
G01X772538Y-152662D02*
Y-140996D01*
G01Y-143912D02*
X773412Y-142454D01*
X774722Y-141287D01*
X776468Y-140996D01*
X777996Y-141287D01*
X779307Y-142454D01*
X779962Y-144495D01*
Y-152662D01*
G01X797680Y-135162D02*
Y-152662D01*
G01Y-150038D02*
X796807Y-151496D01*
X795496Y-152370D01*
X793968Y-152662D01*
X792222Y-152079D01*
X790912Y-150621D01*
X790038Y-148871D01*
X789820Y-146829D01*
X790038Y-144787D01*
X790912Y-143037D01*
X792222Y-141579D01*
X793968Y-140996D01*
X795496Y-141287D01*
X796588Y-141871D01*
X797680Y-143037D01*
G01X828750Y-135162D02*
Y-152662D01*
G01X825693Y-140996D02*
X831807D01*
G01X842538Y-152662D02*
Y-135162D01*
G01Y-143620D02*
X843630Y-142162D01*
X844722Y-141287D01*
X846468Y-140996D01*
X847778Y-141287D01*
X849307Y-142454D01*
X849962Y-144204D01*
Y-152662D01*
G01X860475Y-144787D02*
X867462D01*
X866807Y-142745D01*
X865715Y-141579D01*
X864187Y-140996D01*
X862658Y-141287D01*
X861348Y-142162D01*
X860475Y-144204D01*
X860038Y-145954D01*
Y-147704D01*
X860475Y-149454D01*
X861567Y-151204D01*
X862877Y-152370D01*
X864405Y-152662D01*
X865933Y-152079D01*
X867462Y-150329D01*
G01X894165D02*
X895912Y-151787D01*
X897877Y-152662D01*
X899623D01*
X901370Y-151787D01*
X902680Y-150329D01*
X903335Y-148287D01*
X902898Y-146246D01*
X901807Y-144495D01*
X899842Y-143329D01*
X897222Y-142745D01*
X895693Y-141579D01*
X895038Y-139537D01*
X895475Y-137495D01*
X896567Y-136037D01*
X898095Y-135162D01*
X899623D01*
X901152Y-135745D01*
X902462Y-137204D01*
G01X920617Y-152662D02*
X911883D01*
Y-135162D01*
X920617D01*
G01X917123Y-143620D02*
X911883D01*
G01X951250Y-140996D02*
Y-152662D01*
G01Y-136329D02*
X950813Y-136037D01*
Y-135454D01*
X951250Y-135162D01*
X951687Y-135454D01*
Y-136037D01*
X951250Y-136329D01*
G01X962200Y-152662D02*
Y-140996D01*
G01Y-144204D02*
X962855Y-142745D01*
X963947Y-141579D01*
X965475Y-140996D01*
X967003Y-141579D01*
X968095Y-142745D01*
X968750Y-144204D01*
Y-152662D01*
G01Y-144204D02*
X969405Y-142745D01*
X970496Y-141579D01*
X972025Y-140996D01*
X973553Y-141579D01*
X974645Y-142745D01*
X975300Y-144495D01*
Y-152662D01*
G01X982320Y-158495D02*
Y-140996D01*
G01Y-143620D02*
X983412Y-142162D01*
X984503Y-141287D01*
X986250Y-140996D01*
X987778Y-141287D01*
X989307Y-142745D01*
X989962Y-144787D01*
X990180Y-146829D01*
X989962Y-148871D01*
X989307Y-150912D01*
X987996Y-152079D01*
X986250Y-152662D01*
X984722Y-152370D01*
X983193Y-151496D01*
X982320Y-150329D01*
G01X1000475Y-144787D02*
X1007462D01*
X1006807Y-142745D01*
X1005715Y-141579D01*
X1004187Y-140996D01*
X1002658Y-141287D01*
X1001348Y-142162D01*
X1000475Y-144204D01*
X1000038Y-145954D01*
Y-147704D01*
X1000475Y-149454D01*
X1001567Y-151204D01*
X1002877Y-152370D01*
X1004405Y-152662D01*
X1005933Y-152079D01*
X1007462Y-150329D01*
G01X1025180Y-135162D02*
Y-152662D01*
G01Y-150038D02*
X1024307Y-151496D01*
X1022996Y-152370D01*
X1021468Y-152662D01*
X1019722Y-152079D01*
X1018412Y-150621D01*
X1017538Y-148871D01*
X1017320Y-146829D01*
X1017538Y-144787D01*
X1018412Y-143037D01*
X1019722Y-141579D01*
X1021468Y-140996D01*
X1022996Y-141287D01*
X1024088Y-141871D01*
X1025180Y-143037D01*
G01X1042680Y-152662D02*
Y-140996D01*
G01Y-143037D02*
X1041807Y-141871D01*
X1040496Y-141287D01*
X1038968Y-140996D01*
X1037440Y-141579D01*
X1036130Y-142745D01*
X1035256Y-144495D01*
X1034820Y-146829D01*
X1035256Y-149162D01*
X1036130Y-150912D01*
X1037440Y-152079D01*
X1038968Y-152662D01*
X1040496Y-152370D01*
X1041807Y-151496D01*
X1042680Y-150329D01*
G01X1052538Y-152662D02*
Y-140996D01*
G01Y-143912D02*
X1053412Y-142454D01*
X1054722Y-141287D01*
X1056468Y-140996D01*
X1057996Y-141287D01*
X1059307Y-142454D01*
X1059962Y-144495D01*
Y-152662D01*
G01X1077243Y-142454D02*
X1075715Y-141287D01*
X1074405Y-140996D01*
X1072658Y-141579D01*
X1071348Y-142745D01*
X1070475Y-144787D01*
X1070256Y-146829D01*
X1070475Y-148871D01*
X1071348Y-150621D01*
X1072658Y-152079D01*
X1074405Y-152662D01*
X1075933Y-152079D01*
X1077243Y-150912D01*
G01X1087975Y-144787D02*
X1094962D01*
X1094307Y-142745D01*
X1093215Y-141579D01*
X1091687Y-140996D01*
X1090158Y-141287D01*
X1088848Y-142162D01*
X1087975Y-144204D01*
X1087538Y-145954D01*
Y-147704D01*
X1087975Y-149454D01*
X1089067Y-151204D01*
X1090377Y-152370D01*
X1091905Y-152662D01*
X1093433Y-152079D01*
X1094962Y-150329D01*
G01X1126250Y-135162D02*
Y-152662D01*
G01X1123193Y-140996D02*
X1129307D01*
G01X1140693Y-152662D02*
Y-140996D01*
G01Y-143329D02*
X1141785Y-142162D01*
X1142877Y-141287D01*
X1144405Y-140996D01*
X1145496Y-141287D01*
X1146807Y-142162D01*
G01X1165180Y-152662D02*
Y-140996D01*
G01Y-143037D02*
X1164307Y-141871D01*
X1162996Y-141287D01*
X1161468Y-140996D01*
X1159940Y-141579D01*
X1158630Y-142745D01*
X1157756Y-144495D01*
X1157320Y-146829D01*
X1157756Y-149162D01*
X1158630Y-150912D01*
X1159940Y-152079D01*
X1161468Y-152662D01*
X1162996Y-152370D01*
X1164307Y-151496D01*
X1165180Y-150329D01*
G01X1182243Y-142454D02*
X1180715Y-141287D01*
X1179405Y-140996D01*
X1177658Y-141579D01*
X1176348Y-142745D01*
X1175475Y-144787D01*
X1175256Y-146829D01*
X1175475Y-148871D01*
X1176348Y-150621D01*
X1177658Y-152079D01*
X1179405Y-152662D01*
X1180933Y-152079D01*
X1182243Y-150912D01*
G01X1192975Y-144787D02*
X1199962D01*
X1199307Y-142745D01*
X1198215Y-141579D01*
X1196687Y-140996D01*
X1195158Y-141287D01*
X1193848Y-142162D01*
X1192975Y-144204D01*
X1192538Y-145954D01*
Y-147704D01*
X1192975Y-149454D01*
X1194067Y-151204D01*
X1195377Y-152370D01*
X1196905Y-152662D01*
X1198433Y-152079D01*
X1199962Y-150329D01*
G01X1210475Y-150621D02*
X1211567Y-151787D01*
X1213095Y-152662D01*
X1214405D01*
X1215715Y-152079D01*
X1216588Y-151204D01*
X1217025Y-150038D01*
X1216807Y-148287D01*
X1215933Y-147412D01*
X1212003Y-145662D01*
X1211130Y-143620D01*
X1211567Y-142162D01*
X1212440Y-141287D01*
X1213750Y-140996D01*
X1215060Y-141287D01*
X1216370Y-142162D01*
G01X1248750Y-140996D02*
Y-152662D01*
G01Y-136329D02*
X1248313Y-136037D01*
Y-135454D01*
X1248750Y-135162D01*
X1249187Y-135454D01*
Y-136037D01*
X1248750Y-136329D01*
G01X1262538Y-152662D02*
Y-140996D01*
G01Y-143912D02*
X1263412Y-142454D01*
X1264722Y-141287D01*
X1266468Y-140996D01*
X1267996Y-141287D01*
X1269307Y-142454D01*
X1269962Y-144495D01*
Y-152662D01*
G01X1301250D02*
Y-135162D01*
G01X1322680Y-152662D02*
Y-140996D01*
G01Y-143037D02*
X1321807Y-141871D01*
X1320496Y-141287D01*
X1318968Y-140996D01*
X1317440Y-141579D01*
X1316130Y-142745D01*
X1315256Y-144495D01*
X1314820Y-146829D01*
X1315256Y-149162D01*
X1316130Y-150912D01*
X1317440Y-152079D01*
X1318968Y-152662D01*
X1320496Y-152370D01*
X1321807Y-151496D01*
X1322680Y-150329D01*
G01X1331665Y-157912D02*
X1332975Y-158495D01*
X1334722Y-157912D01*
X1335813Y-156746D01*
X1336687Y-155287D01*
X1337996Y-150621D01*
X1340835Y-140996D01*
G01X1333848D02*
X1337996Y-150621D01*
G01X1350475Y-144787D02*
X1357462D01*
X1356807Y-142745D01*
X1355715Y-141579D01*
X1354187Y-140996D01*
X1352658Y-141287D01*
X1351348Y-142162D01*
X1350475Y-144204D01*
X1350038Y-145954D01*
Y-147704D01*
X1350475Y-149454D01*
X1351567Y-151204D01*
X1352877Y-152370D01*
X1354405Y-152662D01*
X1355933Y-152079D01*
X1357462Y-150329D01*
G01X1368193Y-152662D02*
Y-140996D01*
G01Y-143329D02*
X1369285Y-142162D01*
X1370377Y-141287D01*
X1371905Y-140996D01*
X1372996Y-141287D01*
X1374307Y-142162D01*
G01X1401883Y-135162D02*
Y-152662D01*
X1410617D01*
G01X1418947Y-149162D02*
X1420256Y-151204D01*
X1422003Y-152370D01*
X1423968Y-152662D01*
X1425715Y-152370D01*
X1427462Y-150912D01*
X1428553Y-149162D01*
X1428772Y-147412D01*
X1428335Y-145371D01*
X1426807Y-143912D01*
X1425278Y-143329D01*
X1423313D01*
G01X1425278D02*
X1426588Y-142454D01*
X1427680Y-140996D01*
X1428117Y-139246D01*
X1427680Y-137495D01*
X1426588Y-136037D01*
X1424623Y-135162D01*
X1422658Y-135454D01*
X1420693Y-136621D01*
G01X1441250Y-153245D02*
X1440813Y-152954D01*
Y-152370D01*
X1441250Y-152079D01*
X1441687Y-152370D01*
Y-152954D01*
X1441250Y-153245D01*
G01X879036Y548599D02*
X880783Y547141D01*
X882748Y546266D01*
X884494D01*
X886241Y547141D01*
X887551Y548599D01*
X888206Y550641D01*
X887769Y552682D01*
X886678Y554433D01*
X884713Y555599D01*
X882093Y556183D01*
X880564Y557349D01*
X879909Y559391D01*
X880346Y561433D01*
X881438Y562891D01*
X882966Y563766D01*
X884494D01*
X886023Y563183D01*
X887333Y561724D01*
G01X905488Y546266D02*
X896754D01*
Y563766D01*
X905488D01*
G01X901994Y555308D02*
X896754D01*
G01X933501Y563766D02*
X938741D01*
G01X936121D02*
Y546266D01*
G01X933501D02*
X938741D01*
G01X947944D02*
Y563766D01*
X953621Y549183D01*
X959298Y563766D01*
Y546266D01*
G01X966754D02*
Y563766D01*
X971994D01*
X973741Y562891D01*
X975051Y560849D01*
X975488Y558516D01*
X975051Y556183D01*
X973959Y554433D01*
X971994Y553557D01*
X966754D01*
G01X992988Y546266D02*
X984254D01*
Y563766D01*
X992988D01*
G01X989494Y555308D02*
X984254D01*
G01X1001318Y546266D02*
Y563766D01*
X1005684D01*
X1007431Y562891D01*
X1008741Y561724D01*
X1009833Y559975D01*
X1010706Y557932D01*
X1010924Y555016D01*
X1010706Y552099D01*
X1009833Y550057D01*
X1008741Y548307D01*
X1007431Y547141D01*
X1005684Y546266D01*
X1001318D01*
G01X1018162D02*
X1023621Y563766D01*
X1029080Y546266D01*
G01X1027114Y552391D02*
X1020127D01*
G01X1036099Y546266D02*
Y563766D01*
X1046143Y546266D01*
Y563766D01*
G01X1063424Y562307D02*
X1062114Y563183D01*
X1060586Y563766D01*
X1058839D01*
X1056874Y562891D01*
X1055346Y561433D01*
X1054254Y559682D01*
X1053381Y556766D01*
X1053162Y554141D01*
X1053599Y551516D01*
X1054254Y549766D01*
X1055564Y548016D01*
X1057093Y546849D01*
X1058621Y546266D01*
X1060149D01*
X1061678Y546849D01*
X1062988Y547724D01*
X1064080Y548890D01*
G01X1080488Y546266D02*
X1071754D01*
Y563766D01*
X1080488D01*
G01X1076994Y555308D02*
X1071754D01*
G01X1111121Y563766D02*
Y546266D01*
G01X1106099Y563766D02*
X1116143D01*
G01X1123162Y546266D02*
X1128621Y563766D01*
X1134080Y546266D01*
G01X1132114Y552391D02*
X1125127D01*
G01X1147867Y555599D02*
X1148741Y556474D01*
X1149396Y557932D01*
X1149833Y559975D01*
X1149396Y561724D01*
X1148523Y562891D01*
X1146994Y563766D01*
X1141099D01*
Y546266D01*
X1148304D01*
X1149833Y547432D01*
X1150706Y549183D01*
X1151143Y551224D01*
X1150706Y553266D01*
X1149396Y555016D01*
X1147867Y555599D01*
X1141099D01*
G01X1159254Y563766D02*
Y546266D01*
X1167988D01*
G01X1185488D02*
X1176754D01*
Y563766D01*
X1185488D01*
G01X1181994Y555308D02*
X1176754D01*
G01X1198621Y545683D02*
X1198184Y545974D01*
Y546558D01*
X1198621Y546849D01*
X1199058Y546558D01*
Y545974D01*
X1198621Y545683D01*
G01Y553557D02*
X1198184Y553849D01*
Y554433D01*
X1198621Y554724D01*
X1199058Y554433D01*
Y553849D01*
X1198621Y553557D01*
G01X1229254Y563766D02*
Y546266D01*
X1237988D01*
G01X1246318Y549766D02*
X1247627Y547724D01*
X1249374Y546558D01*
X1251339Y546266D01*
X1253086Y546558D01*
X1254833Y548016D01*
X1255924Y549766D01*
X1256143Y551516D01*
X1255706Y553557D01*
X1254178Y555016D01*
X1252649Y555599D01*
X1250684D01*
G01X1252649D02*
X1253959Y556474D01*
X1255051Y557932D01*
X1255488Y559682D01*
X1255051Y561433D01*
X1253959Y562891D01*
X1251994Y563766D01*
X1250029Y563474D01*
X1248064Y562307D01*
G01X933518Y479590D02*
X934827Y478132D01*
X936356Y477258D01*
X938321Y476966D01*
X940286Y477549D01*
X941814Y478716D01*
X942906Y480757D01*
X943124Y483091D01*
X942688Y485424D01*
X941596Y486883D01*
X940067Y488049D01*
X938539Y488341D01*
X937011Y488049D01*
X935046Y486883D01*
X935701Y494466D01*
X941596D01*
G01X955821D02*
X954074Y493883D01*
X952764Y492424D01*
X951891Y490675D01*
X951236Y488341D01*
X951018Y485716D01*
X951236Y483091D01*
X951891Y480757D01*
X952764Y479007D01*
X954074Y477549D01*
X955821Y476966D01*
X957567Y477549D01*
X958878Y479007D01*
X959751Y480757D01*
X960406Y483091D01*
X960624Y485716D01*
X960406Y488341D01*
X959751Y490675D01*
X958878Y492424D01*
X957567Y493883D01*
X955821Y494466D01*
G01X973321Y476383D02*
X972884Y476674D01*
Y477258D01*
X973321Y477549D01*
X973758Y477258D01*
Y476674D01*
X973321Y476383D01*
G01X990821Y494466D02*
X989074Y493883D01*
X987764Y492424D01*
X986891Y490675D01*
X986236Y488341D01*
X986018Y485716D01*
X986236Y483091D01*
X986891Y480757D01*
X987764Y479007D01*
X989074Y477549D01*
X990821Y476966D01*
X992567Y477549D01*
X993878Y479007D01*
X994751Y480757D01*
X995406Y483091D01*
X995624Y485716D01*
X995406Y488341D01*
X994751Y490675D01*
X993878Y492424D01*
X992567Y493883D01*
X990821Y494466D01*
G01X900701Y529116D02*
X905941D01*
G01X903321D02*
Y511616D01*
G01X900701D02*
X905941D01*
G01X915144D02*
Y529116D01*
X920821Y514533D01*
X926498Y529116D01*
Y511616D01*
G01X933954D02*
Y529116D01*
X939194D01*
X940941Y528241D01*
X942251Y526199D01*
X942688Y523866D01*
X942251Y521533D01*
X941159Y519783D01*
X939194Y518907D01*
X933954D01*
G01X954729Y505783D02*
X952546Y508699D01*
X951454Y511616D01*
Y523282D01*
X952546Y526199D01*
X954729Y529116D01*
G01X973321Y511616D02*
X971574Y511908D01*
X970046Y513074D01*
X968736Y514824D01*
X967862Y516866D01*
X967426Y519199D01*
Y521533D01*
X967862Y523866D01*
X968736Y525908D01*
X970046Y527657D01*
X971574Y528824D01*
X973321Y529116D01*
X975067Y528824D01*
X976596Y527657D01*
X977906Y525908D01*
X978780Y523866D01*
X979216Y521533D01*
Y519199D01*
X978780Y516866D01*
X977906Y514824D01*
X976596Y513074D01*
X975067Y511908D01*
X973321Y511616D01*
G01X987109D02*
Y529116D01*
G01Y520658D02*
X988201Y522116D01*
X989293Y522991D01*
X991039Y523282D01*
X992349Y522991D01*
X993878Y521824D01*
X994533Y520074D01*
Y511616D01*
G01X1001771D02*
Y523282D01*
G01Y520074D02*
X1002426Y521533D01*
X1003518Y522699D01*
X1005046Y523282D01*
X1006574Y522699D01*
X1007666Y521533D01*
X1008321Y520074D01*
Y511616D01*
G01Y520074D02*
X1008976Y521533D01*
X1010067Y522699D01*
X1011596Y523282D01*
X1013124Y522699D01*
X1014216Y521533D01*
X1014871Y519783D01*
Y511616D01*
G01X1026913Y505783D02*
X1029096Y508699D01*
X1030188Y511616D01*
Y523282D01*
X1029096Y526199D01*
X1026913Y529116D01*
G01X1071771D02*
X1074827Y511616D01*
X1078321Y529116D01*
X1081814Y511616D01*
X1084871Y529116D01*
G01X1093201D02*
X1098441D01*
G01X1095821D02*
Y511616D01*
G01X1093201D02*
X1098441D01*
G01X1108518D02*
Y529116D01*
X1112884D01*
X1114631Y528241D01*
X1115941Y527074D01*
X1117033Y525325D01*
X1117906Y523282D01*
X1118124Y520366D01*
X1117906Y517449D01*
X1117033Y515407D01*
X1115941Y513657D01*
X1114631Y512491D01*
X1112884Y511616D01*
X1108518D01*
G01X1130821Y529116D02*
Y511616D01*
G01X1125799Y529116D02*
X1135843D01*
G01X1143736Y511616D02*
Y529116D01*
G01X1152906D02*
Y511616D01*
G01Y520366D02*
X1143736D01*
G01X1164729Y505783D02*
X1162546Y508699D01*
X1161454Y511616D01*
Y523282D01*
X1162546Y526199D01*
X1164729Y529116D01*
G01X1176771Y511616D02*
Y523282D01*
G01Y520074D02*
X1177426Y521533D01*
X1178518Y522699D01*
X1180046Y523282D01*
X1181574Y522699D01*
X1182666Y521533D01*
X1183321Y520074D01*
Y511616D01*
G01Y520074D02*
X1183976Y521533D01*
X1185067Y522699D01*
X1186596Y523282D01*
X1188124Y522699D01*
X1189216Y521533D01*
X1189871Y519783D01*
Y511616D01*
G01X1200821Y523282D02*
Y511616D01*
G01Y527949D02*
X1200384Y528241D01*
Y528824D01*
X1200821Y529116D01*
X1201258Y528824D01*
Y528241D01*
X1200821Y527949D01*
G01X1218321Y511616D02*
Y529116D01*
G01X1232546Y513657D02*
X1233638Y512491D01*
X1235166Y511616D01*
X1236476D01*
X1237786Y512199D01*
X1238659Y513074D01*
X1239096Y514240D01*
X1238878Y515991D01*
X1238004Y516866D01*
X1234074Y518616D01*
X1233201Y520658D01*
X1233638Y522116D01*
X1234511Y522991D01*
X1235821Y523282D01*
X1237131Y522991D01*
X1238441Y522116D01*
G01X1254413Y505783D02*
X1256596Y508699D01*
X1257688Y511616D01*
Y523282D01*
X1256596Y526199D01*
X1254413Y529116D01*
G01X1143518Y479590D02*
X1144827Y478132D01*
X1146356Y477258D01*
X1148321Y476966D01*
X1150286Y477549D01*
X1151814Y478716D01*
X1152906Y480757D01*
X1153124Y483091D01*
X1152688Y485424D01*
X1151596Y486883D01*
X1150067Y488049D01*
X1148539Y488341D01*
X1147011Y488049D01*
X1145046Y486883D01*
X1145701Y494466D01*
X1151596D01*
G01X1165821Y476383D02*
X1165384Y476674D01*
Y477258D01*
X1165821Y477549D01*
X1166258Y477258D01*
Y476674D01*
X1165821Y476383D01*
G01X1183321Y494466D02*
X1181574Y493883D01*
X1180264Y492424D01*
X1179391Y490675D01*
X1178736Y488341D01*
X1178518Y485716D01*
X1178736Y483091D01*
X1179391Y480757D01*
X1180264Y479007D01*
X1181574Y477549D01*
X1183321Y476966D01*
X1185067Y477549D01*
X1186378Y479007D01*
X1187251Y480757D01*
X1187906Y483091D01*
X1188124Y485716D01*
X1187906Y488341D01*
X1187251Y490675D01*
X1186378Y492424D01*
X1185067Y493883D01*
X1183321Y494466D01*
G01X1318736Y479299D02*
X1320483Y477841D01*
X1322448Y476966D01*
X1324194D01*
X1325941Y477841D01*
X1327251Y479299D01*
X1327906Y481341D01*
X1327469Y483382D01*
X1326378Y485133D01*
X1324413Y486299D01*
X1321793Y486883D01*
X1320264Y488049D01*
X1319609Y490091D01*
X1320046Y492133D01*
X1321138Y493591D01*
X1322666Y494466D01*
X1324194D01*
X1325723Y493883D01*
X1327033Y492424D01*
G01X1345188Y476966D02*
X1336454D01*
Y494466D01*
X1345188D01*
G01X1341694Y486008D02*
X1336454D01*
G01X1305821Y529116D02*
Y511616D01*
G01X1300799Y529116D02*
X1310843D01*
G01X1323321Y511616D02*
Y519491D01*
X1318954Y529116D01*
G01X1327688D02*
X1323321Y519491D01*
G01X1336454Y511616D02*
Y529116D01*
X1341694D01*
X1343441Y528241D01*
X1344751Y526199D01*
X1345188Y523866D01*
X1344751Y521533D01*
X1343659Y519783D01*
X1341694Y518907D01*
X1336454D01*
G01X1362688Y511616D02*
X1353954D01*
Y529116D01*
X1362688D01*
G01X1359194Y520658D02*
X1353954D01*
G01X1406454Y511616D02*
Y529116D01*
X1411913D01*
X1413659Y528241D01*
X1414751Y527074D01*
X1415188Y524741D01*
X1414751Y522407D01*
X1413441Y520949D01*
X1411913Y520074D01*
X1406454D01*
G01X1411913D02*
X1415188Y511616D01*
G01X1425046Y519491D02*
X1432033D01*
X1431378Y521533D01*
X1430286Y522699D01*
X1428758Y523282D01*
X1427229Y522991D01*
X1425919Y522116D01*
X1425046Y520074D01*
X1424609Y518324D01*
Y516574D01*
X1425046Y514824D01*
X1426138Y513074D01*
X1427448Y511908D01*
X1428976Y511616D01*
X1430504Y512199D01*
X1432033Y513949D01*
G01X1444511Y511616D02*
Y526491D01*
X1444948Y527949D01*
X1445821Y528824D01*
X1447131Y529116D01*
X1448441Y528533D01*
X1449096Y527074D01*
G01X1446476Y522116D02*
X1442109D01*
G01X1463321Y511033D02*
X1462884Y511324D01*
Y511908D01*
X1463321Y512199D01*
X1463758Y511908D01*
Y511324D01*
X1463321Y511033D01*
G01X1493954Y511616D02*
Y529116D01*
X1499194D01*
X1500941Y528241D01*
X1502251Y526199D01*
X1502688Y523866D01*
X1502251Y521533D01*
X1501159Y519783D01*
X1499194Y518907D01*
X1493954D01*
G01X1515821Y511616D02*
Y529116D01*
G01X1537251Y511616D02*
Y523282D01*
G01Y521241D02*
X1536378Y522407D01*
X1535067Y522991D01*
X1533539Y523282D01*
X1532011Y522699D01*
X1530701Y521533D01*
X1529827Y519783D01*
X1529391Y517449D01*
X1529827Y515116D01*
X1530701Y513366D01*
X1532011Y512199D01*
X1533539Y511616D01*
X1535067Y511908D01*
X1536378Y512782D01*
X1537251Y513949D01*
G01X1547109Y511616D02*
Y523282D01*
G01Y520366D02*
X1547983Y521824D01*
X1549293Y522991D01*
X1551039Y523282D01*
X1552567Y522991D01*
X1553878Y521824D01*
X1554533Y519783D01*
Y511616D01*
G01X1565046Y519491D02*
X1572033D01*
X1571378Y521533D01*
X1570286Y522699D01*
X1568758Y523282D01*
X1567229Y522991D01*
X1565919Y522116D01*
X1565046Y520074D01*
X1564609Y518324D01*
Y516574D01*
X1565046Y514824D01*
X1566138Y513074D01*
X1567448Y511908D01*
X1568976Y511616D01*
X1570504Y512199D01*
X1572033Y513949D01*
G01X1450204Y494466D02*
Y476966D01*
X1458938D01*
G01X1467923Y491549D02*
X1469233Y493299D01*
X1470761Y494174D01*
X1472508Y494466D01*
X1474691Y493883D01*
X1476219Y492424D01*
X1476656Y490675D01*
X1476438Y488924D01*
X1475564Y487466D01*
X1471198Y484549D01*
X1469233Y482508D01*
X1467923Y479590D01*
X1467486Y476966D01*
X1476656D01*
G01X1485641Y476383D02*
X1493501Y494466D01*
G01X1502704D02*
Y476966D01*
X1511438D01*
G01X1527191D02*
Y494466D01*
X1519112Y481924D01*
X1530030D01*
G01X1686121Y488632D02*
Y476966D01*
G01Y493299D02*
X1685684Y493591D01*
Y494174D01*
X1686121Y494466D01*
X1686558Y494174D01*
Y493591D01*
X1686121Y493299D01*
G01X1700346Y479007D02*
X1701438Y477841D01*
X1702966Y476966D01*
X1704276D01*
X1705586Y477549D01*
X1706459Y478424D01*
X1706896Y479590D01*
X1706678Y481341D01*
X1705804Y482216D01*
X1701874Y483966D01*
X1701001Y486008D01*
X1701438Y487466D01*
X1702311Y488341D01*
X1703621Y488632D01*
X1704931Y488341D01*
X1706241Y487466D01*
G01X1733599Y476966D02*
Y494466D01*
X1743643Y476966D01*
Y494466D01*
G01X1756121Y476966D02*
X1754374Y477258D01*
X1752846Y478424D01*
X1751536Y480174D01*
X1750662Y482216D01*
X1750226Y484549D01*
Y486883D01*
X1750662Y489216D01*
X1751536Y491258D01*
X1752846Y493007D01*
X1754374Y494174D01*
X1756121Y494466D01*
X1757867Y494174D01*
X1759396Y493007D01*
X1760706Y491258D01*
X1761580Y489216D01*
X1762016Y486883D01*
Y484549D01*
X1761580Y482216D01*
X1760706Y480174D01*
X1759396Y478424D01*
X1757867Y477258D01*
X1756121Y476966D01*
G01X1773621Y494466D02*
Y476966D01*
G01X1768599Y494466D02*
X1778643D01*
G01X1804909Y488632D02*
Y480466D01*
X1805783Y478424D01*
X1807093Y477258D01*
X1808621Y476966D01*
X1810149Y477258D01*
X1811459Y478424D01*
X1812333Y480466D01*
G01Y476966D02*
Y488632D01*
G01X1822846Y479007D02*
X1823938Y477841D01*
X1825466Y476966D01*
X1826776D01*
X1828086Y477549D01*
X1828959Y478424D01*
X1829396Y479590D01*
X1829178Y481341D01*
X1828304Y482216D01*
X1824374Y483966D01*
X1823501Y486008D01*
X1823938Y487466D01*
X1824811Y488341D01*
X1826121Y488632D01*
X1827431Y488341D01*
X1828741Y487466D01*
G01X1840346Y484841D02*
X1847333D01*
X1846678Y486883D01*
X1845586Y488049D01*
X1844058Y488632D01*
X1842529Y488341D01*
X1841219Y487466D01*
X1840346Y485424D01*
X1839909Y483674D01*
Y481924D01*
X1840346Y480174D01*
X1841438Y478424D01*
X1842748Y477258D01*
X1844276Y476966D01*
X1845804Y477549D01*
X1847333Y479299D01*
G01X1865051Y494466D02*
Y476966D01*
G01Y479590D02*
X1864178Y478132D01*
X1862867Y477258D01*
X1861339Y476966D01*
X1859593Y477549D01*
X1858283Y479007D01*
X1857409Y480757D01*
X1857191Y482799D01*
X1857409Y484841D01*
X1858283Y486591D01*
X1859593Y488049D01*
X1861339Y488632D01*
X1862867Y488341D01*
X1863959Y487757D01*
X1865051Y486591D01*
G01X1611318Y511033D02*
X1620924Y523866D01*
G01X1616121Y526199D02*
Y508699D01*
G01X1620924Y511033D02*
X1611318Y523866D01*
G01X1609571Y517449D02*
X1622671D01*
G01X1648283D02*
X1653959D01*
G01X1681318Y511616D02*
Y529116D01*
X1685684D01*
X1687431Y528241D01*
X1688741Y527074D01*
X1689833Y525325D01*
X1690706Y523282D01*
X1690924Y520366D01*
X1690706Y517449D01*
X1689833Y515407D01*
X1688741Y513657D01*
X1687431Y512491D01*
X1685684Y511616D01*
X1681318D01*
G01X1700346Y519491D02*
X1707333D01*
X1706678Y521533D01*
X1705586Y522699D01*
X1704058Y523282D01*
X1702529Y522991D01*
X1701219Y522116D01*
X1700346Y520074D01*
X1699909Y518324D01*
Y516574D01*
X1700346Y514824D01*
X1701438Y513074D01*
X1702748Y511908D01*
X1704276Y511616D01*
X1705804Y512199D01*
X1707333Y513949D01*
G01X1717409Y511616D02*
Y523282D01*
G01Y520366D02*
X1718283Y521824D01*
X1719593Y522991D01*
X1721339Y523282D01*
X1722867Y522991D01*
X1724178Y521824D01*
X1724833Y519783D01*
Y511616D01*
G01X1738621D02*
X1737311Y511908D01*
X1736001Y513074D01*
X1735127Y515116D01*
X1734691Y517449D01*
X1735127Y519783D01*
X1736001Y521824D01*
X1737311Y522991D01*
X1738621Y523282D01*
X1739931Y522991D01*
X1741241Y521824D01*
X1742114Y519783D01*
X1742333Y517449D01*
X1742114Y515116D01*
X1741241Y513074D01*
X1739931Y511908D01*
X1738621Y511616D01*
G01X1756121Y529116D02*
Y511616D01*
G01X1753064Y523282D02*
X1759178D01*
G01X1770346Y519491D02*
X1777333D01*
X1776678Y521533D01*
X1775586Y522699D01*
X1774058Y523282D01*
X1772529Y522991D01*
X1771219Y522116D01*
X1770346Y520074D01*
X1769909Y518324D01*
Y516574D01*
X1770346Y514824D01*
X1771438Y513074D01*
X1772748Y511908D01*
X1774276Y511616D01*
X1775804Y512199D01*
X1777333Y513949D01*
G01X1787846Y513657D02*
X1788938Y512491D01*
X1790466Y511616D01*
X1791776D01*
X1793086Y512199D01*
X1793959Y513074D01*
X1794396Y514240D01*
X1794178Y515991D01*
X1793304Y516866D01*
X1789374Y518616D01*
X1788501Y520658D01*
X1788938Y522116D01*
X1789811Y522991D01*
X1791121Y523282D01*
X1792431Y522991D01*
X1793741Y522116D01*
G01X1826121Y529116D02*
Y511616D01*
G01X1823064Y523282D02*
X1829178D01*
G01X1839909Y511616D02*
Y529116D01*
G01Y520658D02*
X1841001Y522116D01*
X1842093Y522991D01*
X1843839Y523282D01*
X1845149Y522991D01*
X1846678Y521824D01*
X1847333Y520074D01*
Y511616D01*
G01X1865051D02*
Y523282D01*
G01Y521241D02*
X1864178Y522407D01*
X1862867Y522991D01*
X1861339Y523282D01*
X1859811Y522699D01*
X1858501Y521533D01*
X1857627Y519783D01*
X1857191Y517449D01*
X1857627Y515116D01*
X1858501Y513366D01*
X1859811Y512199D01*
X1861339Y511616D01*
X1862867Y511908D01*
X1864178Y512782D01*
X1865051Y513949D01*
G01X1878621Y529116D02*
Y511616D01*
G01X1875564Y523282D02*
X1881678D01*
G01X1913621Y529116D02*
Y511616D01*
G01X1910564Y523282D02*
X1916678D01*
G01X1927409Y511616D02*
Y529116D01*
G01Y520658D02*
X1928501Y522116D01*
X1929593Y522991D01*
X1931339Y523282D01*
X1932649Y522991D01*
X1934178Y521824D01*
X1934833Y520074D01*
Y511616D01*
G01X1948621Y523282D02*
Y511616D01*
G01Y527949D02*
X1948184Y528241D01*
Y528824D01*
X1948621Y529116D01*
X1949058Y528824D01*
Y528241D01*
X1948621Y527949D01*
G01X1962846Y513657D02*
X1963938Y512491D01*
X1965466Y511616D01*
X1966776D01*
X1968086Y512199D01*
X1968959Y513074D01*
X1969396Y514240D01*
X1969178Y515991D01*
X1968304Y516866D01*
X1964374Y518616D01*
X1963501Y520658D01*
X1963938Y522116D01*
X1964811Y522991D01*
X1966121Y523282D01*
X1967431Y522991D01*
X1968741Y522116D01*
G01X1998501Y529116D02*
X2003741D01*
G01X2001121D02*
Y511616D01*
G01X1998501D02*
X2003741D01*
G01X2012071D02*
Y523282D01*
G01Y520074D02*
X2012726Y521533D01*
X2013818Y522699D01*
X2015346Y523282D01*
X2016874Y522699D01*
X2017966Y521533D01*
X2018621Y520074D01*
Y511616D01*
G01Y520074D02*
X2019276Y521533D01*
X2020367Y522699D01*
X2021896Y523282D01*
X2023424Y522699D01*
X2024516Y521533D01*
X2025171Y519783D01*
Y511616D01*
G01X2032191Y505783D02*
Y523282D01*
G01Y520658D02*
X2033283Y522116D01*
X2034374Y522991D01*
X2036121Y523282D01*
X2037649Y522991D01*
X2039178Y521533D01*
X2039833Y519491D01*
X2040051Y517449D01*
X2039833Y515407D01*
X2039178Y513366D01*
X2037867Y512199D01*
X2036121Y511616D01*
X2034593Y511908D01*
X2033064Y512782D01*
X2032191Y513949D01*
G01X2050346Y519491D02*
X2057333D01*
X2056678Y521533D01*
X2055586Y522699D01*
X2054058Y523282D01*
X2052529Y522991D01*
X2051219Y522116D01*
X2050346Y520074D01*
X2049909Y518324D01*
Y516574D01*
X2050346Y514824D01*
X2051438Y513074D01*
X2052748Y511908D01*
X2054276Y511616D01*
X2055804Y512199D01*
X2057333Y513949D01*
G01X2075051Y529116D02*
Y511616D01*
G01Y514240D02*
X2074178Y512782D01*
X2072867Y511908D01*
X2071339Y511616D01*
X2069593Y512199D01*
X2068283Y513657D01*
X2067409Y515407D01*
X2067191Y517449D01*
X2067409Y519491D01*
X2068283Y521241D01*
X2069593Y522699D01*
X2071339Y523282D01*
X2072867Y522991D01*
X2073959Y522407D01*
X2075051Y521241D01*
G01X2092551Y511616D02*
Y523282D01*
G01Y521241D02*
X2091678Y522407D01*
X2090367Y522991D01*
X2088839Y523282D01*
X2087311Y522699D01*
X2086001Y521533D01*
X2085127Y519783D01*
X2084691Y517449D01*
X2085127Y515116D01*
X2086001Y513366D01*
X2087311Y512199D01*
X2088839Y511616D01*
X2090367Y511908D01*
X2091678Y512782D01*
X2092551Y513949D01*
G01X2102409Y511616D02*
Y523282D01*
G01Y520366D02*
X2103283Y521824D01*
X2104593Y522991D01*
X2106339Y523282D01*
X2107867Y522991D01*
X2109178Y521824D01*
X2109833Y519783D01*
Y511616D01*
G01X2127114Y521824D02*
X2125586Y522991D01*
X2124276Y523282D01*
X2122529Y522699D01*
X2121219Y521533D01*
X2120346Y519491D01*
X2120127Y517449D01*
X2120346Y515407D01*
X2121219Y513657D01*
X2122529Y512199D01*
X2124276Y511616D01*
X2125804Y512199D01*
X2127114Y513366D01*
G01X2137846Y519491D02*
X2144833D01*
X2144178Y521533D01*
X2143086Y522699D01*
X2141558Y523282D01*
X2140029Y522991D01*
X2138719Y522116D01*
X2137846Y520074D01*
X2137409Y518324D01*
Y516574D01*
X2137846Y514824D01*
X2138938Y513074D01*
X2140248Y511908D01*
X2141776Y511616D01*
X2143304Y512199D01*
X2144833Y513949D01*
G01X20103Y-86244D02*
G03I-4291J0D01*
G01X0Y-87362D02*
G03X15000Y-102362I15000J0D01*
G01X0Y-11811D02*
Y-87362D01*
G01X3937Y-7874D02*
G03X0Y-11811I0J-3937D01*
G01X15748Y-7874D02*
X3937D01*
G01X0Y7874D02*
G03X7874Y0I7874J0D01*
G01X818897D02*
X7874D01*
G01X0Y7874D02*
Y562992D01*
G01X7874Y570866D02*
G03X0Y562992I0J-7874D01*
G01X7874Y570866D02*
X326781D01*
G01X312004Y-102362D02*
X15000D01*
G01X46456Y0D02*
G03Y-7874I0J-3937D01*
G01X15748D02*
G03Y0I0J3937D01*
G01X287400Y-7874D02*
X46456D01*
G01X40452Y499724D02*
G03I-3051J0D01*
G01X41535Y535157D02*
G03I-4134J0D01*
G01X44685Y517441D02*
G03I-7284J0D01*
G01X121082Y39055D02*
G03I-5019J0D01*
G01X120807Y14567D02*
G03I-4744J0D01*
G01X319878Y-102362D02*
G03X312004I-3937J0D01*
G01X811771D02*
X319878D01*
G01X326770Y0D02*
G03Y-7874I0J-3937D01*
G01X287400D02*
G03Y0I0J3937D01*
G01X302165Y531496D02*
G03I-6890J0D01*
G01X597707Y-7874D02*
X326770D01*
G01X379921Y156220D02*
G03I-5906J0D01*
G01X342529Y530315D02*
G03X334655I-3937J0D01*
G01X342529Y520720D02*
G03X352474Y509057I11811J0D01*
G01X334655Y520720D02*
G03X351230Y501282I19685J0D01*
G01X384484Y503937D02*
X352475Y509057D01*
G01X383858Y496063D02*
X351231Y501282D01*
G01X442287Y503937D02*
X384484D01*
G01X442913Y496063D02*
X383858D01*
G01X342529Y530315D02*
Y520720D01*
G01X334655Y562992D02*
Y520720D01*
G01X346466Y570866D02*
G03X342529Y566929I0J-3937D01*
G01X334655Y555512D02*
G03X342529I3937J0D01*
G01X346466Y570866D02*
X480325D01*
G01X334655Y562992D02*
G03X326781Y570866I-7874J0D01*
G01X342529Y566929D02*
Y555512D01*
G01X415943Y539991D02*
G03I-4291J0D01*
G01X474316Y509060D02*
X442287Y503937D01*
G01X475560Y501285D02*
X442913Y496063D01*
G01X492136Y530315D02*
G03X484262I-3937J0D01*
G01X474316Y509060D02*
G03X484262Y520723I-1865J11663D01*
G01X475560Y501285D02*
G03X492136Y520723I-3109J19438D01*
G01X484262Y530315D02*
Y520723D01*
G01X492136Y562992D02*
Y520723D01*
G01X484262Y566929D02*
G03X480325Y570866I-3937J0D01*
G01X484262Y555512D02*
G03X492136I3937J0D01*
G01X500010Y570866D02*
G03X492136Y562992I0J-7874D01*
G01X500010Y570866D02*
X818897D01*
G01X484262Y566929D02*
Y555512D01*
G01X537401Y371299D02*
G03I-5905J0D01*
G01X538386Y531496D02*
G03I-6890J0D01*
G01X628416Y0D02*
G03Y-7874I0J-3937D01*
G01X597707D02*
G03Y0I0J3937D01*
G01X780315Y-7874D02*
X628416D01*
G01X602362Y116141D02*
G03I-5906J0D01*
G01X817003Y-86834D02*
G03I-4292J0D01*
G01X811771Y-102362D02*
G03X826771Y-87362I0J15000D01*
G01X811023Y0D02*
G03Y-7874I0J-3937D01*
G01X780315D02*
G03Y0I0J3937D01*
G01X822834Y-7874D02*
X811023D01*
G01X818897Y0D02*
G03X826771Y7874I0J7874D01*
G01X818897Y0D02*
X807086D01*
G01X787401Y198819D02*
G03I-5905J0D01*
G01X792421Y499724D02*
G03I-3051J0D01*
G01X793504Y535157D02*
G03I-4134J0D01*
G01X796653Y517441D02*
G03I-7283J0D01*
G01X826771Y562992D02*
G03X818897Y570866I-7874J0D01*
G01X826771Y-11811D02*
Y-87362D01*
G01Y-11811D02*
G03X822834Y-7874I-3937J0D01*
G01X826771Y562992D02*
Y7874D01*
M02*
